FILE_TYPE = MACRO_DRAWING;
SET COLOR_WIRE YELLOW;
SET COLOR_PROP ORANGE;
SET COLOR_DOT WHITE;
SET COLOR_ARC YELLOW;
SET COLOR_BODY GREEN;
SET COLOR_NOTE PURPLE;
SET PROP_DISPLAY VALUE;
SET PAGE_NUMBER P201;
FORCEADD Q_RES..1
(-1275 5200);
FORCEPROP 1 LAST PART_NUMBER CS-1002FB04
J 0
(-1375 5075);
DISPLAY 0.510638 (-1375 5075);
DISPLAY INVISIBLE (-1375 5075);
FORCEPROP 1 LAST MATERIAL CHIP
J 0
(-1150 5200);
DISPLAY 0.510638 (-1150 5200);
FORCEPROP 1 LAST TOLERANCE 1%
J 0
(-1250 5150);
DISPLAY 0.510638 (-1250 5150);
FORCEPROP 1 LAST VALUE 1
J 2
(-1275 5150);
DISPLAY 0.510638 (-1275 5150);
FORCEPROP 1 LAST WATTAGE 1/16W
J 2
(-1275 5100);
DISPLAY 0.510638 (-1275 5100);
FORCEPROP 1 LAST PACK_TYPE 0402LF
J 0
(-1250 5100);
DISPLAY 0.510638 (-1250 5100);
FORCEPROP 1 LAST $LOCATION R4077
J 0
(-1400 5200);
DISPLAY 0.638298 (-1400 5200);
FORCEPROP 1 LASTPIN (-1375 5200) $PN 1
J 0
(-1363 5212);
DISPLAY 0.787234 (-1363 5212);
PAINT MONO (-1363 5212);
FORCEPROP 1 LASTPIN (-1175 5200) $PN 2
J 0
(-1213 5212);
DISPLAY 0.787234 (-1213 5212);
PAINT MONO (-1213 5212);
FORCEPROP 2 LAST CDS_LIB pure_quanta
J 0
(-1275 5200);
DISPLAY INVISIBLE (-1275 5200);
FORCEPROP 1 LAST PATH I102
J 0
(-1325 5350);
DISPLAY 0.978723 (-1325 5350);
PAINT WHITE (-1325 5350);
DISPLAY INVISIBLE (-1325 5350);
FORCEPROP 0 LAST CDS_LOCATION R4077
J 0
(-1400 5250);
DISPLAY 1.021277 (-1400 5250);
DISPLAY INVISIBLE (-1400 5250);
FORCEPROP 0 LAST $SEC 1
J 0
(-1400 5250);
DISPLAY 0.680851 (-1400 5250);
PAINT MONO (-1400 5250);
DISPLAY INVISIBLE (-1400 5250);
FORCEPROP 0 LAST CDS_SEC 1
J 0
(-1400 5250);
DISPLAY 1.021277 (-1400 5250);
DISPLAY INVISIBLE (-1400 5250);
FORCEADD Q_CAP..1
(-1050 4975);
FORCEPROP 1 LAST PART_NUMBER CH5104KEB02
J 0
(-1000 4875);
DISPLAY 0.510638 (-1000 4875);
DISPLAY INVISIBLE (-1000 4875);
FORCEPROP 1 LAST VALUE 1UF
J 0
(-1000 5125);
DISPLAY 0.638298 (-1000 5125);
FORCEPROP 1 LAST VOLTAGE 25V
J 0
(-1000 5075);
DISPLAY 0.638298 (-1000 5075);
FORCEPROP 1 LAST MATERIAL X6S
J 0
(-1000 4975);
DISPLAY 0.638298 (-1000 4975);
FORCEPROP 1 LAST PACK_TYPE C0402
J 0
(-1000 4925);
DISPLAY 0.638298 (-1000 4925);
FORCEPROP 1 LAST TOLERANCE 10%
J 0
(-1000 5025);
DISPLAY 0.638298 (-1000 5025);
FORCEPROP 1 LAST $LOCATION C1884
J 0
(-1000 5175);
DISPLAY 0.638298 (-1000 5175);
FORCEPROP 1 LASTPIN (-1050 5075) $PN 1
J 0
(-1040 5055);
DISPLAY 0.787234 (-1040 5055);
PAINT MONO (-1040 5055);
FORCEPROP 1 LASTPIN (-1050 4875) $PN 2
J 0
(-1040 4855);
DISPLAY 0.787234 (-1040 4855);
PAINT MONO (-1040 4855);
FORCEPROP 2 LAST CDS_LIB pure_quanta
J 0
(-1050 4975);
DISPLAY INVISIBLE (-1050 4975);
FORCEPROP 2 LAST BOM_COST VR_SYSTEM 
J 0
(-1000 5125);
DISPLAY 0.680851 (-1000 5125);
DISPLAY INVISIBLE (-1000 5125);
FORCEPROP 1 LAST PATH I103
J 0
(-1000 5125);
DISPLAY 0.978723 (-1000 5125);
PAINT WHITE (-1000 5125);
DISPLAY INVISIBLE (-1000 5125);
FORCEPROP 0 LAST CDS_LOCATION C1884
J 0
(-1000 5125);
DISPLAY 1.021277 (-1000 5125);
DISPLAY INVISIBLE (-1000 5125);
FORCEPROP 0 LAST $SEC 1
J 0
(-1000 5125);
DISPLAY 0.680851 (-1000 5125);
PAINT MONO (-1000 5125);
DISPLAY INVISIBLE (-1000 5125);
FORCEPROP 0 LAST CDS_SEC 1
J 0
(-1000 5125);
DISPLAY 1.021277 (-1000 5125);
DISPLAY INVISIBLE (-1000 5125);
FORCEADD Q_CAP..1
(-2400 5000);
FORCEPROP 1 LAST PART_NUMBER CH4104K1B00
J 0
(-2350 4850);
DISPLAY 0.808511 (-2350 4850);
DISPLAY INVISIBLE (-2350 4850);
FORCEPROP 1 LAST PACK_TYPE 0402
J 0
(-2350 4850);
DISPLAY 0.638298 (-2350 4850);
FORCEPROP 1 LAST TOLERANCE 10%
J 0
(-2350 4950);
DISPLAY 0.638298 (-2350 4950);
FORCEPROP 1 LAST VOLTAGE 25V
J 0
(-2350 5000);
DISPLAY 0.638298 (-2350 5000);
FORCEPROP 1 LAST MATERIAL X7R
J 0
(-2350 4900);
DISPLAY 0.638298 (-2350 4900);
FORCEPROP 1 LAST VALUE 0.1UF
J 0
(-2350 5050);
DISPLAY 0.638298 (-2350 5050);
FORCEPROP 1 LAST $LOCATION C2257
J 0
(-2350 5100);
DISPLAY 0.787234 (-2350 5100);
FORCEPROP 1 LASTPIN (-2400 5100) $PN 1
J 0
(-2390 5080);
DISPLAY 0.787234 (-2390 5080);
PAINT MONO (-2390 5080);
FORCEPROP 1 LASTPIN (-2400 4900) $PN 2
J 0
(-2390 4880);
DISPLAY 0.787234 (-2390 4880);
PAINT MONO (-2390 4880);
FORCEPROP 2 LAST CDS_LIB pure_quanta
J 0
(-2400 5000);
DISPLAY INVISIBLE (-2400 5000);
FORCEPROP 1 LAST PATH I104
J 0
(-2350 5150);
DISPLAY 0.978723 (-2350 5150);
PAINT WHITE (-2350 5150);
DISPLAY INVISIBLE (-2350 5150);
FORCEPROP 0 LAST CDS_LOCATION C2257
J 0
(-2350 5150);
DISPLAY 1.021277 (-2350 5150);
DISPLAY INVISIBLE (-2350 5150);
FORCEPROP 0 LAST $SEC 1
J 0
(-2350 5150);
DISPLAY 0.680851 (-2350 5150);
PAINT MONO (-2350 5150);
DISPLAY INVISIBLE (-2350 5150);
FORCEPROP 0 LAST CDS_SEC 1
J 0
(-2350 5150);
DISPLAY 1.021277 (-2350 5150);
DISPLAY INVISIBLE (-2350 5150);
FORCEADD Q_CAP..1
(-1600 5000);
FORCEPROP 1 LAST PART_NUMBER CH4104K1B00
J 0
(-1550 4850);
DISPLAY 0.808511 (-1550 4850);
DISPLAY INVISIBLE (-1550 4850);
FORCEPROP 1 LAST VALUE 0.1UF
J 0
(-1550 5050);
DISPLAY 0.638298 (-1550 5050);
FORCEPROP 1 LAST VOLTAGE 25V
J 0
(-1550 5000);
DISPLAY 0.638298 (-1550 5000);
FORCEPROP 1 LAST TOLERANCE 10%
J 0
(-1550 4950);
DISPLAY 0.638298 (-1550 4950);
FORCEPROP 1 LAST MATERIAL X7R
J 0
(-1550 4900);
DISPLAY 0.638298 (-1550 4900);
FORCEPROP 1 LAST PACK_TYPE 0402
J 0
(-1550 4850);
DISPLAY 0.638298 (-1550 4850);
FORCEPROP 1 LAST $LOCATION C2258
J 0
(-1550 5100);
DISPLAY 0.638298 (-1550 5100);
FORCEPROP 1 LASTPIN (-1600 5100) $PN 1
J 0
(-1590 5080);
DISPLAY 0.787234 (-1590 5080);
PAINT MONO (-1590 5080);
FORCEPROP 1 LASTPIN (-1600 4900) $PN 2
J 0
(-1590 4880);
DISPLAY 0.787234 (-1590 4880);
PAINT MONO (-1590 4880);
FORCEPROP 1 LAST PATH I105
J 0
(-1550 5150);
DISPLAY 0.978723 (-1550 5150);
PAINT WHITE (-1550 5150);
DISPLAY INVISIBLE (-1550 5150);
FORCEPROP 2 LAST CDS_LIB pure_quanta
J 0
(-1600 5000);
DISPLAY INVISIBLE (-1600 5000);
FORCEPROP 0 LAST CDS_LOCATION C2258
J 0
(-1550 5150);
DISPLAY 1.021277 (-1550 5150);
DISPLAY INVISIBLE (-1550 5150);
FORCEPROP 0 LAST $SEC 1
J 0
(-1550 5150);
DISPLAY 0.680851 (-1550 5150);
PAINT MONO (-1550 5150);
DISPLAY INVISIBLE (-1550 5150);
FORCEPROP 0 LAST CDS_SEC 1
J 0
(-1550 5150);
DISPLAY 1.021277 (-1550 5150);
DISPLAY INVISIBLE (-1550 5150);
FORCEADD Q_CAP..1
(-725 4975);
FORCEPROP 1 LAST PART_NUMBER CH4104K1B00
J 0
(-675 4825);
DISPLAY 0.808511 (-675 4825);
DISPLAY INVISIBLE (-675 4825);
FORCEPROP 1 LAST MATERIAL X7R
J 0
(-675 4875);
DISPLAY 0.638298 (-675 4875);
FORCEPROP 1 LAST PACK_TYPE 0402
J 0
(-675 4825);
DISPLAY 0.638298 (-675 4825);
FORCEPROP 1 LAST VALUE 0.1UF
J 0
(-675 5025);
DISPLAY 0.638298 (-675 5025);
FORCEPROP 1 LAST VOLTAGE 25V
J 0
(-675 4975);
DISPLAY 0.638298 (-675 4975);
FORCEPROP 1 LAST TOLERANCE 10%
J 0
(-675 4925);
DISPLAY 0.638298 (-675 4925);
FORCEPROP 1 LAST $LOCATION C2259
J 0
(-675 5075);
DISPLAY 0.787234 (-675 5075);
FORCEPROP 1 LASTPIN (-725 5075) $PN 1
J 0
(-715 5055);
DISPLAY 0.787234 (-715 5055);
PAINT MONO (-715 5055);
FORCEPROP 1 LASTPIN (-725 4875) $PN 2
J 0
(-715 4855);
DISPLAY 0.787234 (-715 4855);
PAINT MONO (-715 4855);
FORCEPROP 1 LAST PATH I106
J 0
(-675 5125);
DISPLAY 0.978723 (-675 5125);
PAINT WHITE (-675 5125);
DISPLAY INVISIBLE (-675 5125);
FORCEPROP 2 LAST CDS_LIB pure_quanta
J 0
(-725 4975);
DISPLAY INVISIBLE (-725 4975);
FORCEPROP 0 LAST CDS_LOCATION C2259
J 0
(-675 5125);
DISPLAY 1.021277 (-675 5125);
DISPLAY INVISIBLE (-675 5125);
FORCEPROP 0 LAST $SEC 1
J 0
(-675 5125);
DISPLAY 0.680851 (-675 5125);
PAINT MONO (-675 5125);
DISPLAY INVISIBLE (-675 5125);
FORCEPROP 0 LAST CDS_SEC 1
J 0
(-675 5125);
DISPLAY 1.021277 (-675 5125);
DISPLAY INVISIBLE (-675 5125);
FORCEADD UNIVERSAL_GND..1
(-725 4650);
FORCEPROP 3 LASTPIN (-725 4700) SIG_NAME GND\g
J 0
(-715 4710);
DISPLAY 0.659574 (-715 4710);
PAINT MONO (-715 4710);
DISPLAY INVISIBLE (-715 4710);
FORCEPROP 1 LAST HDL_POWER GND
J 1
(-700 4575);
DISPLAY 0.872340 (-700 4575);
PAINT GREEN (-700 4575);
DISPLAY INVISIBLE (-700 4575);
FORCEPROP 1 LAST PATH I107
J 0
(-650 4650);
DISPLAY 0.872340 (-650 4650);
PAINT AQUA (-650 4650);
DISPLAY INVISIBLE (-650 4650);
FORCEPROP 2 LAST CDS_LIB logical_power
J 0
(-725 4650);
DISPLAY INVISIBLE (-725 4650);
FORCEADD UNIVERSAL_POWER..1
(-2400 5350);
FORCEPROP 3 LASTPIN (-2400 5300) SIG_NAME VFG3P3_CLK_GEN\g
J 0
(-2390 5310);
DISPLAY 0.659574 (-2390 5310);
PAINT MONO (-2390 5310);
DISPLAY INVISIBLE (-2390 5310);
FORCEPROP 1 LAST HDL_POWER VFG3P3_CLK_GEN
J 1
(-2400 5400);
DISPLAY 0.872340 (-2400 5400);
PAINT GREEN (-2400 5400);
FORCEPROP 2 LAST CDS_LIB logical_power
J 0
(-2400 5350);
DISPLAY INVISIBLE (-2400 5350);
FORCEPROP 1 LAST PATH I108
J 0
(-2350 5375);
DISPLAY 0.872340 (-2350 5375);
PAINT AQUA (-2350 5375);
DISPLAY INVISIBLE (-2350 5375);
FORCEADD UNIVERSAL_POWER..1
(-725 5300);
FORCEPROP 3 LASTPIN (-725 5250) SIG_NAME VFG_3P3A_CLK_GEN\g
J 0
(-715 5260);
DISPLAY 0.659574 (-715 5260);
PAINT MONO (-715 5260);
DISPLAY INVISIBLE (-715 5260);
FORCEPROP 1 LAST HDL_POWER VFG_3P3A_CLK_GEN
J 1
(-725 5350);
DISPLAY 0.872340 (-725 5350);
PAINT GREEN (-725 5350);
FORCEPROP 1 LAST PATH I109
J 0
(-675 5325);
DISPLAY 0.872340 (-675 5325);
PAINT AQUA (-675 5325);
DISPLAY INVISIBLE (-675 5325);
FORCEPROP 2 LAST CDS_LIB logical_power
J 0
(-725 5300);
DISPLAY INVISIBLE (-725 5300);
FORCEADD UNIVERSAL_POWER..1
(-2850 4300);
FORCEPROP 3 LASTPIN (-2850 4250) SIG_NAME VFG3P3_CLK_GEN\g
J 0
(-2840 4260);
DISPLAY 0.659574 (-2840 4260);
PAINT MONO (-2840 4260);
DISPLAY INVISIBLE (-2840 4260);
FORCEPROP 1 LAST HDL_POWER VFG3P3_CLK_GEN
J 1
(-2850 4350);
DISPLAY 0.872340 (-2850 4350);
PAINT GREEN (-2850 4350);
FORCEPROP 1 LAST PATH I110
J 0
(-2800 4325);
DISPLAY 0.872340 (-2800 4325);
PAINT AQUA (-2800 4325);
DISPLAY INVISIBLE (-2800 4325);
FORCEPROP 2 LAST CDS_LIB logical_power
J 0
(-2850 4300);
DISPLAY INVISIBLE (-2850 4300);
FORCEADD UNIVERSAL_POWER..1
(-2500 4375);
FORCEPROP 3 LASTPIN (-2500 4325) SIG_NAME VFG_3P3A_CLK_GEN\g
J 0
(-2490 4335);
DISPLAY 0.659574 (-2490 4335);
PAINT MONO (-2490 4335);
DISPLAY INVISIBLE (-2490 4335);
FORCEPROP 1 LAST HDL_POWER VFG_3P3A_CLK_GEN
J 1
(-2500 4425);
DISPLAY 0.872340 (-2500 4425);
PAINT GREEN (-2500 4425);
FORCEPROP 1 LAST PATH I111
J 0
(-2450 4400);
DISPLAY 0.872340 (-2450 4400);
PAINT AQUA (-2450 4400);
DISPLAY INVISIBLE (-2450 4400);
FORCEPROP 2 LAST CDS_LIB logical_power
J 0
(-2500 4375);
DISPLAY INVISIBLE (-2500 4375);
FORCEADD UNIVERSAL_GND..1
(-4350 3500);
FORCEPROP 3 LASTPIN (-4350 3550) SIG_NAME GND\g
J 0
(-4340 3560);
DISPLAY 0.659574 (-4340 3560);
PAINT MONO (-4340 3560);
DISPLAY INVISIBLE (-4340 3560);
FORCEPROP 1 LAST HDL_POWER GND
J 1
(-4325 3425);
DISPLAY 0.872340 (-4325 3425);
PAINT GREEN (-4325 3425);
DISPLAY INVISIBLE (-4325 3425);
FORCEPROP 2 LAST CDS_LIB logical_power
J 0
(-4350 3500);
DISPLAY INVISIBLE (-4350 3500);
FORCEPROP 1 LAST PATH I113
J 0
(-4275 3500);
DISPLAY 0.872340 (-4275 3500);
PAINT AQUA (-4275 3500);
DISPLAY INVISIBLE (-4275 3500);
FORCEADD UNIVERSAL_GND..1
(-4225 3600);
FORCEPROP 3 LASTPIN (-4225 3650) SIG_NAME GND\g
J 0
(-4215 3660);
DISPLAY 0.659574 (-4215 3660);
PAINT MONO (-4215 3660);
DISPLAY INVISIBLE (-4215 3660);
FORCEPROP 1 LAST PATH I115
J 0
(-4150 3600);
DISPLAY 0.872340 (-4150 3600);
PAINT AQUA (-4150 3600);
DISPLAY INVISIBLE (-4150 3600);
FORCEPROP 2 LAST CDS_LIB logical_power
J 0
(-4225 3600);
DISPLAY INVISIBLE (-4225 3600);
FORCEPROP 1 LAST HDL_POWER GND
J 1
(-4200 3525);
DISPLAY 0.872340 (-4200 3525);
PAINT GREEN (-4200 3525);
DISPLAY INVISIBLE (-4200 3525);
FORCEADD UNIVERSAL_GND..1
(-3575 3600);
FORCEPROP 3 LASTPIN (-3575 3650) SIG_NAME GND\g
J 0
(-3565 3660);
DISPLAY 0.659574 (-3565 3660);
PAINT MONO (-3565 3660);
DISPLAY INVISIBLE (-3565 3660);
FORCEPROP 1 LAST PATH I116
J 0
(-3500 3600);
DISPLAY 0.872340 (-3500 3600);
PAINT AQUA (-3500 3600);
DISPLAY INVISIBLE (-3500 3600);
FORCEPROP 1 LAST HDL_POWER GND
J 1
(-3550 3525);
DISPLAY 0.872340 (-3550 3525);
PAINT GREEN (-3550 3525);
DISPLAY INVISIBLE (-3550 3525);
FORCEPROP 2 LAST CDS_LIB logical_power
J 0
(-3575 3600);
DISPLAY INVISIBLE (-3575 3600);
FORCEADD UNIVERSAL_GND..1
(-3475 3475);
FORCEPROP 3 LASTPIN (-3475 3525) SIG_NAME GND\g
J 0
(-3465 3535);
DISPLAY 0.659574 (-3465 3535);
PAINT MONO (-3465 3535);
DISPLAY INVISIBLE (-3465 3535);
FORCEPROP 1 LAST PATH I117
J 0
(-3400 3475);
DISPLAY 0.872340 (-3400 3475);
PAINT AQUA (-3400 3475);
DISPLAY INVISIBLE (-3400 3475);
FORCEPROP 1 LAST HDL_POWER GND
J 1
(-3450 3400);
DISPLAY 0.872340 (-3450 3400);
PAINT GREEN (-3450 3400);
DISPLAY INVISIBLE (-3450 3400);
FORCEPROP 2 LAST CDS_LIB logical_power
J 0
(-3475 3475);
DISPLAY INVISIBLE (-3475 3475);
FORCEADD OFFPAGE..3
R 2
(-3050 3450);
FORCEPROP 2 LAST $XR0 241 
J 0
(-3630 3450);
DISPLAY 0.638298 (-3630 3450);
PAINT MONO (-3630 3450);
FORCEPROP 2 LAST CDS_LIB standard
J 2
(-3050 3450);
PAINT MONO (-3050 3450);
DISPLAY INVISIBLE (-3050 3450);
FORCEPROP 1 LAST OFFPAGE TRUE
J 2
(-3375 3325);
DISPLAY 0.872340 (-3375 3325);
PAINT GREEN (-3375 3325);
DISPLAY INVISIBLE (-3375 3325);
FORCEPROP 1 LAST COMMENT_BODY TRUE
J 2
(-3000 3350);
DISPLAY 0.872340 (-3000 3350);
PAINT GREEN (-3000 3350);
DISPLAY INVISIBLE (-3000 3350);
FORCEPROP 2 LAST PATH I125
J 0
(-3325 3500);
DISPLAY 1.021277 (-3325 3500);
DISPLAY INVISIBLE (-3325 3500);
FORCEADD OFFPAGE..2
R 2
(-3050 3500);
FORCEPROP 2 LAST $XR0 241 
J 0
(-3305 3500);
DISPLAY 0.638298 (-3305 3500);
PAINT MONO (-3305 3500);
FORCEPROP 2 LAST CDS_LIB standard
J 2
(-3050 3500);
PAINT MONO (-3050 3500);
DISPLAY INVISIBLE (-3050 3500);
FORCEPROP 1 LAST COMMENT_BODY TRUE
J 2
(-3005 3405);
DISPLAY 0.872340 (-3005 3405);
PAINT GREEN (-3005 3405);
DISPLAY INVISIBLE (-3005 3405);
FORCEPROP 1 LAST OFFPAGE TRUE
J 2
(-3375 3375);
DISPLAY 0.872340 (-3375 3375);
PAINT GREEN (-3375 3375);
DISPLAY INVISIBLE (-3375 3375);
FORCEPROP 2 LAST PATH I126
J 0
(-3325 3550);
DISPLAY 1.021277 (-3325 3550);
DISPLAY INVISIBLE (-3325 3550);
FORCEADD Q_RES..2
R 2
(250 1475);
FORCEPROP 1 LAST PART_NUMBER CS31002FB08
J 2
(210 1300);
DISPLAY 0.638298 (210 1300);
DISPLAY INVISIBLE (210 1300);
FORCEPROP 1 LAST MATERIAL EMPTY
J 2
(210 1400);
DISPLAY 0.638298 (210 1400);
PAINT RED (210 1400);
FORCEPROP 1 LAST TOLERANCE 1%
J 2
(205 1500);
DISPLAY 0.638298 (205 1500);
FORCEPROP 1 LAST VALUE 10K
J 2
(205 1550);
DISPLAY 0.638298 (205 1550);
FORCEPROP 1 LAST WATTAGE 1/16W
J 2
(210 1450);
DISPLAY 0.638298 (210 1450);
FORCEPROP 1 LAST PACK_TYPE 0402LF
J 2
(210 1350);
DISPLAY 0.638298 (210 1350);
FORCEPROP 1 LAST $LOCATION R4078
J 2
(205 1600);
DISPLAY 0.638298 (205 1600);
FORCEPROP 1 LASTPIN (250 1575) $PN 1
J 2
(245 1537);
DISPLAY 0.787234 (245 1537);
PAINT MONO (245 1537);
FORCEPROP 1 LASTPIN (250 1375) $PN 2
J 2
(245 1385);
DISPLAY 0.787234 (245 1385);
PAINT MONO (245 1385);
FORCEPROP 1 LAST PATH I127
J 2
(200 1650);
DISPLAY 0.978723 (200 1650);
PAINT WHITE (200 1650);
DISPLAY INVISIBLE (200 1650);
FORCEPROP 2 LAST CDS_LIB pure_quanta
J 0
(250 1475);
DISPLAY INVISIBLE (250 1475);
FORCEPROP 0 LAST CDS_LOCATION R4078
J 0
(225 1650);
DISPLAY 1.021277 (225 1650);
DISPLAY INVISIBLE (225 1650);
FORCEPROP 0 LAST $SEC 1
J 0
(225 1650);
DISPLAY 0.680851 (225 1650);
PAINT MONO (225 1650);
DISPLAY INVISIBLE (225 1650);
FORCEPROP 0 LAST CDS_SEC 1
J 0
(225 1650);
DISPLAY 1.021277 (225 1650);
DISPLAY INVISIBLE (225 1650);
FORCEADD Q_RES..2
R 2
(250 1000);
FORCEPROP 1 LAST PART_NUMBER CS31002FB08
J 2
(210 825);
DISPLAY 0.638298 (210 825);
DISPLAY INVISIBLE (210 825);
FORCEPROP 1 LAST TOLERANCE 1%
J 2
(205 1025);
DISPLAY 0.638298 (205 1025);
FORCEPROP 1 LAST VALUE 10K
J 2
(205 1075);
DISPLAY 0.638298 (205 1075);
FORCEPROP 1 LAST PACK_TYPE 0402LF
J 2
(210 875);
DISPLAY 0.638298 (210 875);
FORCEPROP 1 LAST WATTAGE 1/16W
J 2
(210 975);
DISPLAY 0.638298 (210 975);
FORCEPROP 1 LAST MATERIAL CHIP
J 2
(210 925);
DISPLAY 0.638298 (210 925);
FORCEPROP 1 LAST $LOCATION R4079
J 2
(205 1125);
DISPLAY 0.638298 (205 1125);
FORCEPROP 1 LASTPIN (250 1100) $PN 1
J 2
(245 1062);
DISPLAY 0.787234 (245 1062);
PAINT MONO (245 1062);
FORCEPROP 1 LASTPIN (250 900) $PN 2
J 2
(245 910);
DISPLAY 0.787234 (245 910);
PAINT MONO (245 910);
FORCEPROP 2 LAST CDS_LIB pure_quanta
J 0
(250 1000);
DISPLAY INVISIBLE (250 1000);
FORCEPROP 1 LAST PATH I128
J 2
(200 1175);
DISPLAY 0.978723 (200 1175);
PAINT WHITE (200 1175);
DISPLAY INVISIBLE (200 1175);
FORCEPROP 0 LAST CDS_LOCATION R4079
J 0
(225 1175);
DISPLAY 1.021277 (225 1175);
DISPLAY INVISIBLE (225 1175);
FORCEPROP 0 LAST $SEC 1
J 0
(225 1175);
DISPLAY 0.680851 (225 1175);
PAINT MONO (225 1175);
DISPLAY INVISIBLE (225 1175);
FORCEPROP 0 LAST CDS_SEC 1
J 0
(225 1175);
DISPLAY 1.021277 (225 1175);
DISPLAY INVISIBLE (225 1175);
FORCEADD OFFPAGE..2
(2275 1250);
FORCEPROP 2 LAST $XR0 212 
J 0
(2464 1250);
DISPLAY 0.638298 (2464 1250);
PAINT MONO (2464 1250);
FORCEPROP 2 LAST PATH I129
J 0
(2475 1300);
DISPLAY 1.021277 (2475 1300);
DISPLAY INVISIBLE (2475 1300);
FORCEPROP 1 LAST OFFPAGE TRUE
J 0
(2600 1125);
DISPLAY 0.872340 (2600 1125);
DISPLAY INVISIBLE (2600 1125);
FORCEPROP 1 LAST COMMENT_BODY TRUE
J 0
(2230 1155);
DISPLAY 0.872340 (2230 1155);
PAINT GREEN (2230 1155);
DISPLAY INVISIBLE (2230 1155);
FORCEPROP 2 LAST CDS_LIB standard
J 0
(2275 1250);
DISPLAY INVISIBLE (2275 1250);
FORCEADD UNIVERSAL_POWER..1
(1575 1775);
FORCEPROP 3 LASTPIN (1575 1725) SIG_NAME P3V3_AUX\g
J 0
(1585 1735);
DISPLAY 0.659574 (1585 1735);
PAINT MONO (1585 1735);
DISPLAY INVISIBLE (1585 1735);
FORCEPROP 1 LAST HDL_POWER P3V3_AUX
J 1
(1575 1825);
DISPLAY 0.872340 (1575 1825);
PAINT GREEN (1575 1825);
FORCEPROP 1 LAST PATH I130
J 0
(1625 1800);
DISPLAY 0.872340 (1625 1800);
PAINT AQUA (1625 1800);
DISPLAY INVISIBLE (1625 1800);
FORCEPROP 2 LAST CDS_LIB logical_power
J 0
(1575 1775);
DISPLAY INVISIBLE (1575 1775);
FORCEADD UNIVERSAL_GND..1
(1575 750);
FORCEPROP 3 LASTPIN (1575 800) SIG_NAME GND\g
J 0
(1585 810);
DISPLAY 0.659574 (1585 810);
PAINT MONO (1585 810);
DISPLAY INVISIBLE (1585 810);
FORCEPROP 1 LAST PATH I133
J 0
(1650 750);
DISPLAY 0.872340 (1650 750);
PAINT AQUA (1650 750);
DISPLAY INVISIBLE (1650 750);
FORCEPROP 1 LAST HDL_POWER GND
J 1
(1600 675);
DISPLAY 0.872340 (1600 675);
PAINT GREEN (1600 675);
DISPLAY INVISIBLE (1600 675);
FORCEPROP 2 LAST CDS_LIB logical_power
J 0
(1575 750);
DISPLAY INVISIBLE (1575 750);
FORCEADD Q_RES..2
R 2
(1575 1025);
FORCEPROP 1 LAST PART_NUMBER CS31002FB08
J 2
(1535 850);
DISPLAY 0.638298 (1535 850);
DISPLAY INVISIBLE (1535 850);
FORCEPROP 1 LAST MATERIAL EMPTY
J 2
(1535 950);
DISPLAY 0.638298 (1535 950);
PAINT RED (1535 950);
FORCEPROP 1 LAST VALUE 10K
J 2
(1530 1100);
DISPLAY 0.638298 (1530 1100);
FORCEPROP 1 LAST WATTAGE 1/16W
J 2
(1535 1000);
DISPLAY 0.638298 (1535 1000);
FORCEPROP 1 LAST TOLERANCE 1%
J 2
(1530 1050);
DISPLAY 0.638298 (1530 1050);
FORCEPROP 1 LAST PACK_TYPE 0402LF
J 2
(1535 900);
DISPLAY 0.638298 (1535 900);
FORCEPROP 1 LAST $LOCATION R4082
J 2
(1530 1150);
DISPLAY 0.638298 (1530 1150);
FORCEPROP 1 LASTPIN (1575 1125) $PN 1
J 2
(1570 1087);
DISPLAY 0.787234 (1570 1087);
PAINT MONO (1570 1087);
FORCEPROP 1 LASTPIN (1575 925) $PN 2
J 2
(1570 935);
DISPLAY 0.787234 (1570 935);
PAINT MONO (1570 935);
FORCEPROP 2 LAST CDS_LIB pure_quanta
J 0
(1575 1025);
DISPLAY INVISIBLE (1575 1025);
FORCEPROP 1 LAST PATH I134
J 2
(1525 1200);
DISPLAY 0.978723 (1525 1200);
PAINT WHITE (1525 1200);
DISPLAY INVISIBLE (1525 1200);
FORCEPROP 0 LAST CDS_LOCATION R4082
J 0
(1550 1200);
DISPLAY 1.021277 (1550 1200);
DISPLAY INVISIBLE (1550 1200);
FORCEPROP 0 LAST $SEC 1
J 0
(1550 1200);
DISPLAY 0.680851 (1550 1200);
PAINT MONO (1550 1200);
DISPLAY INVISIBLE (1550 1200);
FORCEPROP 0 LAST CDS_SEC 1
J 0
(1550 1200);
DISPLAY 1.021277 (1550 1200);
DISPLAY INVISIBLE (1550 1200);
FORCEADD Q_RES..2
R 2
(1575 1500);
FORCEPROP 1 LAST PART_NUMBER CS31002FB08
J 2
(1535 1325);
DISPLAY 0.638298 (1535 1325);
DISPLAY INVISIBLE (1535 1325);
FORCEPROP 1 LAST TOLERANCE 1%
J 2
(1530 1525);
DISPLAY 0.638298 (1530 1525);
FORCEPROP 1 LAST VALUE 10K
J 2
(1530 1575);
DISPLAY 0.638298 (1530 1575);
FORCEPROP 1 LAST WATTAGE 1/16W
J 2
(1535 1475);
DISPLAY 0.638298 (1535 1475);
FORCEPROP 1 LAST PACK_TYPE 0402LF
J 2
(1535 1375);
DISPLAY 0.638298 (1535 1375);
FORCEPROP 1 LAST MATERIAL CHIP
J 2
(1535 1425);
DISPLAY 0.638298 (1535 1425);
FORCEPROP 1 LAST $LOCATION R4081
J 2
(1530 1625);
DISPLAY 0.638298 (1530 1625);
FORCEPROP 1 LASTPIN (1575 1600) $PN 1
J 2
(1570 1562);
DISPLAY 0.787234 (1570 1562);
PAINT MONO (1570 1562);
FORCEPROP 1 LASTPIN (1575 1400) $PN 2
J 2
(1570 1410);
DISPLAY 0.787234 (1570 1410);
PAINT MONO (1570 1410);
FORCEPROP 1 LAST PATH I135
J 2
(1525 1675);
DISPLAY 0.978723 (1525 1675);
PAINT WHITE (1525 1675);
DISPLAY INVISIBLE (1525 1675);
FORCEPROP 2 LAST CDS_LIB pure_quanta
J 0
(1575 1500);
DISPLAY INVISIBLE (1575 1500);
FORCEPROP 0 LAST CDS_LOCATION R4081
J 0
(1550 1675);
DISPLAY 1.021277 (1550 1675);
DISPLAY INVISIBLE (1550 1675);
FORCEPROP 0 LAST $SEC 1
J 0
(1550 1675);
DISPLAY 0.680851 (1550 1675);
PAINT MONO (1550 1675);
DISPLAY INVISIBLE (1550 1675);
FORCEPROP 0 LAST CDS_SEC 1
J 0
(1550 1675);
DISPLAY 1.021277 (1550 1675);
DISPLAY INVISIBLE (1550 1675);
FORCEADD OFFPAGE..2
(-875 1250);
FORCEPROP 2 LAST $XR2 212 
J 0
(-446 1250);
DISPLAY 0.638298 (-446 1250);
PAINT MONO (-446 1250);
FORCEPROP 2 LAST $XR1 167 
J 0
(-566 1250);
DISPLAY 0.638298 (-566 1250);
PAINT MONO (-566 1250);
FORCEPROP 2 LAST $XR0 166 
J 0
(-686 1250);
DISPLAY 0.638298 (-686 1250);
PAINT MONO (-686 1250);
FORCEPROP 2 LAST PATH I139
J 0
(-675 1300);
DISPLAY 1.021277 (-675 1300);
DISPLAY INVISIBLE (-675 1300);
FORCEPROP 2 LAST CDS_LIB standard
J 2
(-875 1250);
DISPLAY INVISIBLE (-875 1250);
FORCEPROP 1 LAST OFFPAGE TRUE
J 0
(-550 1125);
DISPLAY 0.872340 (-550 1125);
PAINT GREEN (-550 1125);
DISPLAY INVISIBLE (-550 1125);
FORCEPROP 1 LAST COMMENT_BODY TRUE
J 0
(-920 1155);
DISPLAY 0.872340 (-920 1155);
PAINT GREEN (-920 1155);
DISPLAY INVISIBLE (-920 1155);
FORCEADD OFFPAGE..2
(2275 2050);
FORCEPROP 2 LAST $XR0 212 
J 0
(2464 2050);
DISPLAY 0.638298 (2464 2050);
PAINT MONO (2464 2050);
FORCEPROP 2 LAST CDS_LIB standard
J 0
(2275 2050);
DISPLAY INVISIBLE (2275 2050);
FORCEPROP 1 LAST COMMENT_BODY TRUE
J 0
(2230 1955);
DISPLAY 0.872340 (2230 1955);
PAINT GREEN (2230 1955);
DISPLAY INVISIBLE (2230 1955);
FORCEPROP 1 LAST OFFPAGE TRUE
J 0
(2600 1925);
DISPLAY 0.872340 (2600 1925);
DISPLAY INVISIBLE (2600 1925);
FORCEPROP 2 LAST PATH I140
J 0
(2475 2100);
DISPLAY 1.021277 (2475 2100);
DISPLAY INVISIBLE (2475 2100);
FORCEADD UNIVERSAL_POWER..1
(1575 2575);
FORCEPROP 3 LASTPIN (1575 2525) SIG_NAME P3V3_AUX\g
J 0
(1585 2535);
DISPLAY 0.659574 (1585 2535);
PAINT MONO (1585 2535);
DISPLAY INVISIBLE (1585 2535);
FORCEPROP 1 LAST HDL_POWER P3V3_AUX
J 1
(1575 2625);
DISPLAY 0.872340 (1575 2625);
PAINT GREEN (1575 2625);
FORCEPROP 1 LAST PATH I141
J 0
(1625 2600);
DISPLAY 0.872340 (1625 2600);
PAINT AQUA (1625 2600);
DISPLAY INVISIBLE (1625 2600);
FORCEPROP 2 LAST CDS_LIB logical_power
J 0
(1575 2575);
DISPLAY INVISIBLE (1575 2575);
FORCEADD Q_RES..2
R 2
(1575 2300);
FORCEPROP 1 LAST PART_NUMBER CS31002FB08
J 2
(1535 2125);
DISPLAY 0.638298 (1535 2125);
DISPLAY INVISIBLE (1535 2125);
FORCEPROP 1 LAST VALUE 10K
J 2
(1530 2375);
DISPLAY 0.638298 (1530 2375);
FORCEPROP 1 LAST TOLERANCE 1%
J 2
(1530 2325);
DISPLAY 0.638298 (1530 2325);
FORCEPROP 1 LAST WATTAGE 1/16W
J 2
(1535 2275);
DISPLAY 0.638298 (1535 2275);
FORCEPROP 1 LAST MATERIAL CHIP
J 2
(1535 2225);
DISPLAY 0.638298 (1535 2225);
FORCEPROP 1 LAST PACK_TYPE 0402LF
J 2
(1535 2175);
DISPLAY 0.638298 (1535 2175);
FORCEPROP 1 LAST $LOCATION R4080
J 2
(1530 2425);
DISPLAY 0.638298 (1530 2425);
FORCEPROP 1 LASTPIN (1575 2400) $PN 1
J 2
(1570 2362);
DISPLAY 0.787234 (1570 2362);
PAINT MONO (1570 2362);
FORCEPROP 1 LASTPIN (1575 2200) $PN 2
J 2
(1570 2210);
DISPLAY 0.787234 (1570 2210);
PAINT MONO (1570 2210);
FORCEPROP 2 LAST CDS_LIB pure_quanta
J 0
(1575 2300);
DISPLAY INVISIBLE (1575 2300);
FORCEPROP 1 LAST PATH I142
J 2
(1525 2475);
DISPLAY 0.978723 (1525 2475);
PAINT WHITE (1525 2475);
DISPLAY INVISIBLE (1525 2475);
FORCEPROP 0 LAST CDS_LOCATION R4080
J 0
(1550 2475);
DISPLAY 1.021277 (1550 2475);
DISPLAY INVISIBLE (1550 2475);
FORCEPROP 0 LAST $SEC 1
J 0
(1550 2475);
DISPLAY 0.680851 (1550 2475);
PAINT MONO (1550 2475);
DISPLAY INVISIBLE (1550 2475);
FORCEPROP 0 LAST CDS_SEC 1
J 0
(1550 2475);
DISPLAY 1.021277 (1550 2475);
DISPLAY INVISIBLE (1550 2475);
FORCEADD Q_RES..1
(-3300 3300);
FORCEPROP 1 LAST PART_NUMBER CS00002JB13
J 0
(-3450 3225);
DISPLAY 0.638298 (-3450 3225);
DISPLAY INVISIBLE (-3450 3225);
FORCEPROP 1 LAST TOLERANCE 5%
J 0
(-3225 3175);
DISPLAY 0.638298 (-3225 3175);
FORCEPROP 1 LAST VALUE 0
J 2
(-3150 3300);
DISPLAY 0.787234 (-3150 3300);
FORCEPROP 1 LAST WATTAGE 1/16W
J 2
(-3225 3125);
DISPLAY 0.638298 (-3225 3125);
FORCEPROP 1 LAST PACK_TYPE 0402LF
J 0
(-3425 3175);
DISPLAY 0.638298 (-3425 3175);
FORCEPROP 1 LAST MATERIAL CHIP
J 0
(-3125 3300);
DISPLAY 0.638298 (-3125 3300);
FORCEPROP 1 LAST $LOCATION R4076
J 0
(-3500 3300);
DISPLAY 0.638298 (-3500 3300);
FORCEPROP 1 LASTPIN (-3400 3300) $PN 1
J 0
(-3388 3312);
DISPLAY 0.787234 (-3388 3312);
PAINT MONO (-3388 3312);
FORCEPROP 1 LASTPIN (-3200 3300) $PN 2
J 0
(-3238 3312);
DISPLAY 0.787234 (-3238 3312);
PAINT MONO (-3238 3312);
FORCEPROP 2 LAST CDS_LIB pure_quanta
J 0
(-3300 3300);
DISPLAY INVISIBLE (-3300 3300);
FORCEPROP 1 LAST PATH I146
J 0
(-3350 3450);
DISPLAY 0.978723 (-3350 3450);
PAINT WHITE (-3350 3450);
DISPLAY INVISIBLE (-3350 3450);
FORCEPROP 0 LAST CDS_LOCATION R4076
J 0
(-3125 3350);
DISPLAY 1.021277 (-3125 3350);
DISPLAY INVISIBLE (-3125 3350);
FORCEPROP 0 LAST $SEC 1
J 0
(-3125 3350);
DISPLAY 0.680851 (-3125 3350);
PAINT MONO (-3125 3350);
DISPLAY INVISIBLE (-3125 3350);
FORCEPROP 0 LAST CDS_SEC 1
J 0
(-3125 3350);
DISPLAY 1.021277 (-3125 3350);
DISPLAY INVISIBLE (-3125 3350);
FORCEADD Q_RES..1
(-3300 3350);
FORCEPROP 1 LAST PART_NUMBER CS00002JB13
J 0
(-3425 3275);
DISPLAY 0.638298 (-3425 3275);
DISPLAY INVISIBLE (-3425 3275);
FORCEPROP 1 LAST VALUE 0
J 2
(-3150 3350);
DISPLAY 0.787234 (-3150 3350);
FORCEPROP 1 LAST MATERIAL CHIP
J 0
(-3125 3350);
DISPLAY 0.638298 (-3125 3350);
FORCEPROP 1 LAST $LOCATION R4075
J 0
(-3500 3350);
DISPLAY 0.638298 (-3500 3350);
FORCEPROP 1 LASTPIN (-3400 3350) $PN 1
J 0
(-3388 3362);
DISPLAY 0.787234 (-3388 3362);
PAINT MONO (-3388 3362);
FORCEPROP 1 LASTPIN (-3200 3350) $PN 2
J 0
(-3238 3362);
DISPLAY 0.787234 (-3238 3362);
PAINT MONO (-3238 3362);
FORCEPROP 1 LAST WATTAGE 1/16W
J 2
(-3225 3175);
DISPLAY 0.638298 (-3225 3175);
DISPLAY INVISIBLE (-3225 3175);
FORCEPROP 1 LAST TOLERANCE 5%
J 0
(-3225 3225);
DISPLAY 0.638298 (-3225 3225);
DISPLAY INVISIBLE (-3225 3225);
FORCEPROP 1 LAST PACK_TYPE 0402LF
J 0
(-3425 3225);
DISPLAY 0.638298 (-3425 3225);
DISPLAY INVISIBLE (-3425 3225);
FORCEPROP 2 LAST CDS_LIB pure_quanta
J 0
(-3300 3350);
DISPLAY INVISIBLE (-3300 3350);
FORCEPROP 1 LAST PATH I147
J 0
(-3350 3500);
DISPLAY 0.978723 (-3350 3500);
PAINT WHITE (-3350 3500);
DISPLAY INVISIBLE (-3350 3500);
FORCEPROP 0 LAST CDS_LOCATION R4075
J 0
(-3125 3400);
DISPLAY 1.021277 (-3125 3400);
DISPLAY INVISIBLE (-3125 3400);
FORCEPROP 0 LAST $SEC 1
J 0
(-3125 3400);
DISPLAY 0.680851 (-3125 3400);
PAINT MONO (-3125 3400);
DISPLAY INVISIBLE (-3125 3400);
FORCEPROP 0 LAST CDS_SEC 1
J 0
(-3125 3400);
DISPLAY 1.021277 (-3125 3400);
DISPLAY INVISIBLE (-3125 3400);
FORCEADD OFFPAGE..1
(-5200 3350);
FORCEPROP 2 LAST $XR0 215 
J 0
(-5482 3350);
DISPLAY 0.638298 (-5482 3350);
PAINT MONO (-5482 3350);
FORCEPROP 1 LAST COMMENT_BODY TRUE
J 0
(-5075 3250);
DISPLAY 1.170213 (-5075 3250);
PAINT GREEN (-5075 3250);
DISPLAY INVISIBLE (-5075 3250);
FORCEPROP 1 LAST OFFPAGE TRUE
J 0
(-4875 3225);
DISPLAY 1.170213 (-4875 3225);
PAINT GREEN (-4875 3225);
DISPLAY INVISIBLE (-4875 3225);
FORCEPROP 2 LAST PATH I150
J 0
(-5150 3425);
DISPLAY 1.021277 (-5150 3425);
DISPLAY INVISIBLE (-5150 3425);
FORCEPROP 2 LAST CDS_LIB standard
J 0
(-5200 3350);
DISPLAY INVISIBLE (-5200 3350);
FORCEADD OFFPAGE..1
(-5200 3300);
FORCEPROP 2 LAST $XR2 167 
J 0
(-5722 3300);
DISPLAY 0.638298 (-5722 3300);
PAINT MONO (-5722 3300);
FORCEPROP 2 LAST $XR1 212 
J 0
(-5602 3300);
DISPLAY 0.638298 (-5602 3300);
PAINT MONO (-5602 3300);
FORCEPROP 2 LAST $XR0 166 
J 0
(-5482 3300);
DISPLAY 0.638298 (-5482 3300);
PAINT MONO (-5482 3300);
FORCEPROP 2 LAST CDS_LIB standard
J 0
(-5200 3300);
DISPLAY INVISIBLE (-5200 3300);
FORCEPROP 2 LAST PATH I151
J 0
(-5150 3375);
DISPLAY 1.021277 (-5150 3375);
DISPLAY INVISIBLE (-5150 3375);
FORCEPROP 1 LAST OFFPAGE TRUE
J 0
(-4875 3175);
DISPLAY 1.170213 (-4875 3175);
PAINT GREEN (-4875 3175);
DISPLAY INVISIBLE (-4875 3175);
FORCEPROP 1 LAST COMMENT_BODY TRUE
J 0
(-5075 3200);
DISPLAY 1.170213 (-5075 3200);
PAINT GREEN (-5075 3200);
DISPLAY INVISIBLE (-5075 3200);
FORCEADD OFFPAGE..1
(-3075 3050);
FORCEPROP 2 LAST $XR0 212 
J 0
(-3357 3050);
DISPLAY 0.638298 (-3357 3050);
PAINT MONO (-3357 3050);
FORCEPROP 1 LAST OFFPAGE TRUE
J 0
(-2750 2925);
DISPLAY 1.170213 (-2750 2925);
PAINT GREEN (-2750 2925);
DISPLAY INVISIBLE (-2750 2925);
FORCEPROP 1 LAST COMMENT_BODY TRUE
J 0
(-2950 2950);
DISPLAY 1.170213 (-2950 2950);
PAINT GREEN (-2950 2950);
DISPLAY INVISIBLE (-2950 2950);
FORCEPROP 2 LAST PATH I152
J 0
(-3025 3125);
DISPLAY 1.021277 (-3025 3125);
DISPLAY INVISIBLE (-3025 3125);
FORCEPROP 2 LAST CDS_LIB standard
J 0
(-3075 3050);
DISPLAY INVISIBLE (-3075 3050);
FORCEADD OFFPAGE..1
(-3075 2950);
FORCEPROP 2 LAST $XR0 212 
J 0
(-3357 2950);
DISPLAY 0.638298 (-3357 2950);
PAINT MONO (-3357 2950);
FORCEPROP 1 LAST OFFPAGE TRUE
J 0
(-2750 2825);
DISPLAY 1.170213 (-2750 2825);
PAINT GREEN (-2750 2825);
DISPLAY INVISIBLE (-2750 2825);
FORCEPROP 1 LAST COMMENT_BODY TRUE
J 0
(-2950 2850);
DISPLAY 1.170213 (-2950 2850);
PAINT GREEN (-2950 2850);
DISPLAY INVISIBLE (-2950 2850);
FORCEPROP 2 LAST PATH I153
J 0
(-3025 3025);
DISPLAY 1.021277 (-3025 3025);
DISPLAY INVISIBLE (-3025 3025);
FORCEPROP 2 LAST CDS_LIB standard
J 0
(-3075 2950);
DISPLAY INVISIBLE (-3075 2950);
FORCEADD OFFPAGE..1
R 2
(-150 4150);
FORCEPROP 2 LAST $XR0 212 
J 0
(36 4150);
DISPLAY 0.638298 (36 4150);
PAINT MONO (36 4150);
FORCEPROP 1 LAST COMMENT_BODY TRUE
J 2
(-275 4050);
DISPLAY 1.170213 (-275 4050);
PAINT GREEN (-275 4050);
DISPLAY INVISIBLE (-275 4050);
FORCEPROP 1 LAST OFFPAGE TRUE
J 2
(-475 4025);
DISPLAY 1.170213 (-475 4025);
PAINT GREEN (-475 4025);
DISPLAY INVISIBLE (-475 4025);
FORCEPROP 2 LAST PATH I154
J 2
(-200 4225);
DISPLAY 1.021277 (-200 4225);
DISPLAY INVISIBLE (-200 4225);
FORCEPROP 2 LAST CDS_LIB standard
J 2
(-150 4150);
DISPLAY INVISIBLE (-150 4150);
FORCEADD Q_INDUCTOR..1
(-3150 5225);
FORCEPROP 1 LAST PART_NUMBER CX601T05003
J 0
(-3275 5335);
DISPLAY 0.723404 (-3275 5335);
PAINT GREEN (-3275 5335);
DISPLAY INVISIBLE (-3275 5335);
FORCEPROP 2 LAST PACK_TYPE SMLF
J 0
(-3275 5475);
DISPLAY 0.638298 (-3275 5475);
FORCEPROP 1 LAST MATERIAL IND
J 0
(-3275 5280);
DISPLAY 0.723404 (-3275 5280);
PAINT GREEN (-3275 5280);
FORCEPROP 2 LAST VALUE FCM2012KF-601T/0.5A
J 0
(-3275 5425);
DISPLAY 0.638298 (-3275 5425);
FORCEPROP 1 LAST LOCATION L17
J 0
(-3275 5385);
DISPLAY 0.723404 (-3275 5385);
PAINT GREEN (-3275 5385);
FORCEPROP 0 LASTPIN (-3250 5200) $PN 1
J 2
(-3260 5210);
DISPLAY 0.680851 (-3260 5210);
PAINT MONO (-3260 5210);
FORCEPROP 0 LASTPIN (-3050 5200) $PN 2
J 0
(-3040 5210);
DISPLAY 0.680851 (-3040 5210);
PAINT MONO (-3040 5210);
FORCEPROP 2 LAST CDS_LIB pure_quanta
J 0
(-3150 5225);
DISPLAY INVISIBLE (-3150 5225);
FORCEPROP 1 LAST PATH I155
J 0
(-3075 5280);
DISPLAY 0.723404 (-3075 5280);
PAINT GREEN (-3075 5280);
DISPLAY INVISIBLE (-3075 5280);
FORCEPROP 1 LAST NEEDS_NO_SIZE TRUE
J 0
(-3150 5225);
DISPLAY 0.468085 (-3150 5225);
PAINT GREEN (-3150 5225);
DISPLAY INVISIBLE (-3150 5225);
FORCEPROP 0 LAST $SEC 1
J 0
(-3275 5525);
DISPLAY 0.680851 (-3275 5525);
PAINT MONO (-3275 5525);
DISPLAY INVISIBLE (-3275 5525);
FORCEPROP 0 LAST CDS_SEC 1
J 0
(-3275 5525);
DISPLAY 1.021277 (-3275 5525);
DISPLAY INVISIBLE (-3275 5525);
FORCEADD UNIVERSAL_POWER..1
(-3425 1875);
FORCEPROP 3 LASTPIN (-3425 1825) SIG_NAME P3V3_AUX\g
J 0
(-3415 1835);
DISPLAY 0.659574 (-3415 1835);
PAINT MONO (-3415 1835);
DISPLAY INVISIBLE (-3415 1835);
FORCEPROP 1 LAST HDL_POWER P3V3_AUX
J 1
(-3425 1925);
DISPLAY 0.872340 (-3425 1925);
PAINT GREEN (-3425 1925);
FORCEPROP 1 LAST PATH I156
J 0
(-3375 1900);
DISPLAY 0.872340 (-3375 1900);
PAINT AQUA (-3375 1900);
DISPLAY INVISIBLE (-3375 1900);
FORCEPROP 2 LAST CDS_LIB logical_power
J 0
(-3425 1875);
DISPLAY INVISIBLE (-3425 1875);
FORCEADD Q_RES..2
(-3425 1600);
FORCEPROP 1 LAST PART_NUMBER CS24702FB06
J 0
(-3385 1475);
DISPLAY 0.787234 (-3385 1475);
DISPLAY INVISIBLE (-3385 1475);
FORCEPROP 1 LAST TOLERANCE 1%
J 0
(-3380 1625);
DISPLAY 0.787234 (-3380 1625);
FORCEPROP 1 LAST VALUE 4.7K
J 0
(-3380 1675);
DISPLAY 0.787234 (-3380 1675);
FORCEPROP 1 LAST PACK_TYPE 0402LF
J 0
(-3385 1425);
DISPLAY 0.787234 (-3385 1425);
FORCEPROP 1 LAST WATTAGE 1/16W
J 0
(-3385 1575);
DISPLAY 0.787234 (-3385 1575);
FORCEPROP 1 LAST MATERIAL CHIP
J 0
(-3385 1525);
DISPLAY 0.787234 (-3385 1525);
FORCEPROP 1 LAST $LOCATION R3322
J 0
(-3375 1725);
DISPLAY 0.787234 (-3375 1725);
FORCEPROP 1 LASTPIN (-3425 1700) $PN 1
J 0
(-3420 1662);
DISPLAY 0.787234 (-3420 1662);
FORCEPROP 1 LASTPIN (-3425 1500) $PN 2
J 0
(-3420 1510);
DISPLAY 0.787234 (-3420 1510);
FORCEPROP 1 LAST PATH I157
J 0
(-3375 1775);
DISPLAY 0.978723 (-3375 1775);
PAINT WHITE (-3375 1775);
DISPLAY INVISIBLE (-3375 1775);
FORCEPROP 2 LAST CDS_LIB pure_quanta
J 0
(-3425 1600);
PAINT MONO (-3425 1600);
DISPLAY INVISIBLE (-3425 1600);
FORCEPROP 2 LAST CDS_LOCATION R3322
J 0
(-3375 1825);
DISPLAY 1.021277 (-3375 1825);
DISPLAY INVISIBLE (-3375 1825);
FORCEPROP 2 LAST $SEC 1
J 0
(-3375 1825);
DISPLAY 0.680851 (-3375 1825);
PAINT MONO (-3375 1825);
DISPLAY INVISIBLE (-3375 1825);
FORCEPROP 2 LAST CDS_SEC 1
J 0
(-3375 1825);
DISPLAY 1.021277 (-3375 1825);
DISPLAY INVISIBLE (-3375 1825);
FORCEADD 74LVC1G32GW..1
(-2225 1250);
FORCEPROP 1 LAST PART_NUMBER ALVC1G32007
J 0
(-2375 1435);
DISPLAY 0.723404 (-2375 1435);
PAINT GREEN (-2375 1435);
DISPLAY INVISIBLE (-2375 1435);
FORCEPROP 1 LAST MATERIAL IC
J 0
(-2375 1385);
DISPLAY 0.723404 (-2375 1385);
PAINT GREEN (-2375 1385);
FORCEPROP 2 LAST VALUE 74LVC1G32GW
J 0
(-2375 1600);
DISPLAY 1.021277 (-2375 1600);
FORCEPROP 2 LAST PACK_TYPE SMLF
J 0
(-2375 1550);
DISPLAY 1.021277 (-2375 1550);
FORCEPROP 1 LAST LOCATION U248
J 0
(-2375 1505);
DISPLAY 0.723404 (-2375 1505);
PAINT GREEN (-2375 1505);
FORCEPROP 0 LASTPIN (-2425 1150) $PN 3
J 2
(-2435 1160);
DISPLAY 0.680851 (-2435 1160);
PAINT MONO (-2435 1160);
FORCEPROP 0 LASTPIN (-2525 1300) $PN 1
J 2
(-2535 1310);
DISPLAY 0.680851 (-2535 1310);
PAINT MONO (-2535 1310);
FORCEPROP 0 LASTPIN (-2525 1200) $PN 2
J 2
(-2535 1210);
DISPLAY 0.680851 (-2535 1210);
PAINT MONO (-2535 1210);
FORCEPROP 0 LASTPIN (-1925 1250) $PN 4
J 0
(-1915 1260);
DISPLAY 0.680851 (-1915 1260);
PAINT MONO (-1915 1260);
FORCEPROP 0 LASTPIN (-2425 1350) $PN 5
J 2
(-2435 1360);
DISPLAY 0.680851 (-2435 1360);
PAINT MONO (-2435 1360);
FORCEPROP 1 LAST NEEDS_NO_SIZE TRUE
J 0
(-2225 1250);
DISPLAY 0.468085 (-2225 1250);
PAINT GREEN (-2225 1250);
DISPLAY INVISIBLE (-2225 1250);
FORCEPROP 1 LAST PATH I158
J 0
(-2200 1380);
DISPLAY 0.723404 (-2200 1380);
PAINT GREEN (-2200 1380);
DISPLAY INVISIBLE (-2200 1380);
FORCEPROP 2 LAST CDS_LIB pure_quanta
J 0
(-2225 1250);
DISPLAY INVISIBLE (-2225 1250);
FORCEPROP 0 LAST $SEC 1
J 0
(-2375 1650);
DISPLAY 0.680851 (-2375 1650);
PAINT MONO (-2375 1650);
DISPLAY INVISIBLE (-2375 1650);
FORCEPROP 0 LAST CDS_SEC 1
J 0
(-2375 1650);
DISPLAY 1.021277 (-2375 1650);
DISPLAY INVISIBLE (-2375 1650);
FORCEADD Q_XTAL_4P_13BI_24GND..1
(-3900 3825);
FORCEPROP 1 LAST PART_NUMBER BG6250000F0
J 0
(-4033 4100);
DISPLAY 0.723404 (-4033 4100);
PAINT GREEN (-4033 4100);
DISPLAY INVISIBLE (-4033 4100);
FORCEPROP 2 LAST PART_TYPE SMLF
J 0
(-4025 4275);
DISPLAY 1.021277 (-4025 4275);
FORCEPROP 2 LAST VALUE 25MHZ
J 0
(-4025 4225);
DISPLAY 1.021277 (-4025 4225);
FORCEPROP 1 LAST MATERIAL MISC
J 0
(-4033 4004);
DISPLAY 0.723404 (-4033 4004);
PAINT GREEN (-4033 4004);
FORCEPROP 1 LAST LOCATION Y3
J 0
(-4025 4175);
DISPLAY 0.723404 (-4025 4175);
PAINT GREEN (-4025 4175);
FORCEPROP 0 LASTPIN (-4175 3700) $PN 2
J 2
(-4185 3710);
DISPLAY 0.680851 (-4185 3710);
PAINT MONO (-4185 3710);
FORCEPROP 0 LASTPIN (-3625 3700) $PN 4
J 0
(-3615 3710);
DISPLAY 0.680851 (-3615 3710);
PAINT MONO (-3615 3710);
FORCEPROP 0 LASTPIN (-4175 3900) $PN 1
J 2
(-4185 3910);
DISPLAY 0.680851 (-4185 3910);
PAINT MONO (-4185 3910);
FORCEPROP 0 LASTPIN (-3625 3900) $PN 3
J 0
(-3615 3910);
DISPLAY 0.680851 (-3615 3910);
PAINT MONO (-3615 3910);
FORCEPROP 1 LAST PIN_NAMES_ROTATE True
J 0
(-3900 3825);
DISPLAY 0.489362 (-3900 3825);
PAINT GREEN (-3900 3825);
DISPLAY INVISIBLE (-3900 3825);
FORCEPROP 1 LAST CDS_LMAN_SYM_OUTLINE -125,175,125,-175
J 0
(-3900 3825);
DISPLAY 0.468085 (-3900 3825);
PAINT GREEN (-3900 3825);
DISPLAY INVISIBLE (-3900 3825);
FORCEPROP 1 LAST PATH I159
J 0
(-3775 3650);
DISPLAY 0.723404 (-3775 3650);
PAINT GREEN (-3775 3650);
DISPLAY INVISIBLE (-3775 3650);
FORCEPROP 2 LAST CDS_LIB pure_quanta
J 0
(-3900 3825);
DISPLAY INVISIBLE (-3900 3825);
FORCEPROP 0 LAST $SEC 1
J 0
(-4025 4325);
DISPLAY 0.680851 (-4025 4325);
PAINT MONO (-4025 4325);
DISPLAY INVISIBLE (-4025 4325);
FORCEPROP 0 LAST CDS_SEC 1
J 0
(-4025 4325);
DISPLAY 1.021277 (-4025 4325);
DISPLAY INVISIBLE (-4025 4325);
FORCEADD Q_CAP..1
(-2800 5000);
FORCEPROP 1 LAST PART_NUMBER CH6104KEA00
J 0
(-2750 4850);
DISPLAY 0.638298 (-2750 4850);
DISPLAY INVISIBLE (-2750 4850);
FORCEPROP 1 LAST VALUE 10UF
J 0
(-2750 5050);
DISPLAY 0.638298 (-2750 5050);
FORCEPROP 1 LAST MATERIAL X6S
J 0
(-2750 4900);
DISPLAY 0.638298 (-2750 4900);
FORCEPROP 1 LAST TOLERANCE 10%
J 0
(-2750 4950);
DISPLAY 0.638298 (-2750 4950);
FORCEPROP 1 LAST VOLTAGE 25V
J 0
(-2750 5000);
DISPLAY 0.638298 (-2750 5000);
FORCEPROP 1 LAST PACK_TYPE C0805
J 0
(-2750 4800);
DISPLAY 0.638298 (-2750 4800);
FORCEPROP 1 LAST $LOCATION C1883
J 0
(-2750 5100);
DISPLAY 0.787234 (-2750 5100);
FORCEPROP 1 LASTPIN (-2800 5100) $PN 1
J 0
(-2790 5080);
DISPLAY 0.787234 (-2790 5080);
PAINT MONO (-2790 5080);
FORCEPROP 1 LASTPIN (-2800 4900) $PN 2
J 0
(-2790 4880);
DISPLAY 0.787234 (-2790 4880);
PAINT MONO (-2790 4880);
FORCEPROP 1 LAST PATH I16
J 0
(-2750 5150);
DISPLAY 0.978723 (-2750 5150);
PAINT WHITE (-2750 5150);
DISPLAY INVISIBLE (-2750 5150);
FORCEPROP 2 LAST CDS_LIB pure_quanta
J 0
(-2800 5000);
DISPLAY INVISIBLE (-2800 5000);
FORCEPROP 0 LAST CDS_LOCATION C1883
J 0
(-2750 5150);
DISPLAY 1.021277 (-2750 5150);
DISPLAY INVISIBLE (-2750 5150);
FORCEPROP 0 LAST $SEC 1
J 0
(-2750 5150);
DISPLAY 0.680851 (-2750 5150);
PAINT MONO (-2750 5150);
DISPLAY INVISIBLE (-2750 5150);
FORCEPROP 0 LAST CDS_SEC 1
J 0
(-2750 5150);
DISPLAY 1.021277 (-2750 5150);
DISPLAY INVISIBLE (-2750 5150);
FORCEADD Q_RES..1
(-3475 4375);
FORCEPROP 1 LAST PART_NUMBER CS00002JB13
J 0
(-3625 4475);
DISPLAY 0.510638 (-3625 4475);
DISPLAY INVISIBLE (-3625 4475);
FORCEPROP 1 LAST MATERIAL CHIP
J 0
(-3625 4525);
DISPLAY 0.510638 (-3625 4525);
FORCEPROP 1 LAST WATTAGE 1/16W
J 2
(-3275 4525);
DISPLAY 0.510638 (-3275 4525);
FORCEPROP 1 LAST VALUE 0
J 2
(-3475 4425);
DISPLAY 0.638298 (-3475 4425);
FORCEPROP 1 LAST TOLERANCE 5%
J 0
(-3450 4425);
DISPLAY 0.638298 (-3450 4425);
FORCEPROP 1 LAST PACK_TYPE 0402LF
J 0
(-3350 4425);
DISPLAY 0.638298 (-3350 4425);
FORCEPROP 1 LAST $LOCATION R4501
J 0
(-3675 4375);
DISPLAY 0.638298 (-3675 4375);
FORCEPROP 1 LASTPIN (-3575 4375) $PN 1
J 0
(-3563 4387);
DISPLAY 0.787234 (-3563 4387);
PAINT MONO (-3563 4387);
FORCEPROP 1 LASTPIN (-3375 4375) $PN 2
J 0
(-3413 4387);
DISPLAY 0.787234 (-3413 4387);
PAINT MONO (-3413 4387);
FORCEPROP 2 LAST CDS_LIB pure_quanta
J 0
(-3475 4375);
DISPLAY INVISIBLE (-3475 4375);
FORCEPROP 1 LAST PATH I160
J 0
(-3525 4525);
DISPLAY 0.978723 (-3525 4525);
PAINT WHITE (-3525 4525);
DISPLAY INVISIBLE (-3525 4525);
FORCEPROP 0 LAST CDS_LOCATION R4501
J 0
(-3275 4550);
DISPLAY 1.021277 (-3275 4550);
DISPLAY INVISIBLE (-3275 4550);
FORCEPROP 0 LAST $SEC 1
J 0
(-3275 4550);
DISPLAY 0.680851 (-3275 4550);
PAINT MONO (-3275 4550);
DISPLAY INVISIBLE (-3275 4550);
FORCEPROP 0 LAST CDS_SEC 1
J 0
(-3275 4550);
DISPLAY 1.021277 (-3275 4550);
DISPLAY INVISIBLE (-3275 4550);
FORCEADD Q_RES..2
(-3400 975);
FORCEPROP 1 LAST PART_NUMBER CS24702FB06
J 0
(-3350 825);
DISPLAY 0.787234 (-3350 825);
DISPLAY INVISIBLE (-3350 825);
FORCEPROP 1 LAST WATTAGE 1/16W
J 0
(-3350 925);
DISPLAY 0.787234 (-3350 925);
FORCEPROP 1 LAST MATERIAL EMPTY
J 0
(-3350 875);
DISPLAY 0.787234 (-3350 875);
PAINT RED (-3350 875);
FORCEPROP 1 LAST PACK_TYPE 0402LF
J 0
(-3350 775);
DISPLAY 0.787234 (-3350 775);
FORCEPROP 1 LAST VALUE 4.7K
J 0
(-3350 1050);
DISPLAY 0.787234 (-3350 1050);
FORCEPROP 1 LAST TOLERANCE 1%
J 0
(-3350 1000);
DISPLAY 0.787234 (-3350 1000);
FORCEPROP 1 LAST $LOCATION R4514
J 0
(-3350 1100);
DISPLAY 0.978723 (-3350 1100);
FORCEPROP 1 LASTPIN (-3400 1075) $PN 1
J 0
(-3395 1037);
DISPLAY 0.787234 (-3395 1037);
PAINT MONO (-3395 1037);
FORCEPROP 1 LASTPIN (-3400 875) $PN 2
J 0
(-3395 885);
DISPLAY 0.787234 (-3395 885);
PAINT MONO (-3395 885);
FORCEPROP 1 LAST PATH I161
J 0
(-3350 1150);
DISPLAY 0.978723 (-3350 1150);
PAINT WHITE (-3350 1150);
DISPLAY INVISIBLE (-3350 1150);
FORCEPROP 2 LAST CDS_LIB pure_quanta
J 0
(-3400 975);
DISPLAY INVISIBLE (-3400 975);
FORCEPROP 0 LAST CDS_LOCATION R4514
J 0
(-3350 1150);
DISPLAY 1.021277 (-3350 1150);
DISPLAY INVISIBLE (-3350 1150);
FORCEPROP 0 LAST $SEC 1
J 0
(-3350 1150);
DISPLAY 0.680851 (-3350 1150);
PAINT MONO (-3350 1150);
DISPLAY INVISIBLE (-3350 1150);
FORCEPROP 0 LAST CDS_SEC 1
J 0
(-3350 1150);
DISPLAY 1.021277 (-3350 1150);
DISPLAY INVISIBLE (-3350 1150);
FORCEADD UNIVERSAL_GND..1
(-3400 525);
FORCEPROP 3 LASTPIN (-3400 575) SIG_NAME GND\g
J 0
(-3390 585);
DISPLAY 0.659574 (-3390 585);
PAINT MONO (-3390 585);
DISPLAY INVISIBLE (-3390 585);
FORCEPROP 2 LAST CDS_LIB logical_power
J 0
(-3400 525);
DISPLAY INVISIBLE (-3400 525);
FORCEPROP 1 LAST PATH I162
J 0
(-3325 525);
DISPLAY 0.872340 (-3325 525);
PAINT AQUA (-3325 525);
DISPLAY INVISIBLE (-3325 525);
FORCEPROP 1 LAST HDL_POWER GND
J 1
(-3375 450);
DISPLAY 0.872340 (-3375 450);
PAINT GREEN (-3375 450);
DISPLAY INVISIBLE (-3375 450);
FORCEADD Q_RES..2
(-5075 3725);
FORCEPROP 1 LAST PART_NUMBER CS31002FB08
J 0
(-5035 3600);
DISPLAY 0.510638 (-5035 3600);
DISPLAY INVISIBLE (-5035 3600);
FORCEPROP 1 LAST TOLERANCE 1%
J 0
(-5030 3750);
DISPLAY 0.510638 (-5030 3750);
FORCEPROP 1 LAST VALUE 10K
J 0
(-5030 3800);
DISPLAY 0.510638 (-5030 3800);
FORCEPROP 1 LAST MATERIAL CHIP
J 0
(-5035 3650);
DISPLAY 0.510638 (-5035 3650);
FORCEPROP 1 LAST WATTAGE 1/16W
J 0
(-5035 3700);
DISPLAY 0.510638 (-5035 3700);
FORCEPROP 1 LAST PACK_TYPE 0402LF
J 0
(-5025 3600);
DISPLAY 0.510638 (-5025 3600);
FORCEPROP 1 LAST $LOCATION R4521
J 0
(-5030 3850);
DISPLAY 0.978723 (-5030 3850);
FORCEPROP 1 LASTPIN (-5075 3825) $PN 1
J 0
(-5070 3787);
DISPLAY 0.787234 (-5070 3787);
PAINT MONO (-5070 3787);
FORCEPROP 1 LASTPIN (-5075 3625) $PN 2
J 0
(-5070 3635);
DISPLAY 0.787234 (-5070 3635);
PAINT MONO (-5070 3635);
FORCEPROP 1 LAST PATH I163
J 0
(-5025 3900);
DISPLAY 0.978723 (-5025 3900);
PAINT WHITE (-5025 3900);
DISPLAY INVISIBLE (-5025 3900);
FORCEPROP 2 LAST CDS_LIB pure_quanta
J 0
(-5075 3725);
DISPLAY INVISIBLE (-5075 3725);
FORCEPROP 0 LAST CDS_LOCATION R4521
J 0
(-5025 3900);
DISPLAY 1.021277 (-5025 3900);
DISPLAY INVISIBLE (-5025 3900);
FORCEPROP 0 LAST $SEC 1
J 0
(-5025 3900);
DISPLAY 0.680851 (-5025 3900);
PAINT MONO (-5025 3900);
DISPLAY INVISIBLE (-5025 3900);
FORCEPROP 0 LAST CDS_SEC 1
J 0
(-5025 3900);
DISPLAY 1.021277 (-5025 3900);
DISPLAY INVISIBLE (-5025 3900);
FORCEADD UNIVERSAL_POWER..1
(-5075 4000);
FORCEPROP 3 LASTPIN (-5075 3950) SIG_NAME P3V3_AUX\g
J 0
(-5065 3960);
DISPLAY 0.659574 (-5065 3960);
PAINT MONO (-5065 3960);
DISPLAY INVISIBLE (-5065 3960);
FORCEPROP 1 LAST HDL_POWER P3V3_AUX
J 1
(-5075 4050);
DISPLAY 0.872340 (-5075 4050);
PAINT GREEN (-5075 4050);
FORCEPROP 1 LAST PATH I164
J 0
(-5025 4025);
DISPLAY 0.872340 (-5025 4025);
PAINT AQUA (-5025 4025);
DISPLAY INVISIBLE (-5025 4025);
FORCEPROP 2 LAST CDS_LIB logical_power
J 0
(-5075 4000);
DISPLAY INVISIBLE (-5075 4000);
FORCEADD Q_CAP..1
(-4350 3700);
FORCEPROP 1 LAST PART_NUMBER CH-8216TB09
J 2
(-4400 3600);
DISPLAY 0.638298 (-4400 3600);
DISPLAY INVISIBLE (-4400 3600);
FORCEPROP 1 LAST MATERIAL NP0
J 2
(-4400 3650);
DISPLAY 0.638298 (-4400 3650);
FORCEPROP 1 LAST TOLERANCE 0.1P
J 2
(-4400 3700);
DISPLAY 0.638298 (-4400 3700);
FORCEPROP 1 LAST VOLTAGE 50V
J 2
(-4400 3750);
DISPLAY 0.638298 (-4400 3750);
FORCEPROP 1 LAST VALUE 8.2PF
J 2
(-4400 3800);
DISPLAY 0.638298 (-4400 3800);
FORCEPROP 1 LAST PACK_TYPE C0402
J 2
(-4400 3550);
DISPLAY 0.638298 (-4400 3550);
FORCEPROP 1 LAST LOCATION C2255
J 2
(-4400 3850);
DISPLAY 0.638298 (-4400 3850);
FORCEPROP 1 LASTPIN (-4350 3800) $PN 1
J 0
(-4340 3780);
DISPLAY 0.787234 (-4340 3780);
PAINT MONO (-4340 3780);
FORCEPROP 1 LASTPIN (-4350 3600) $PN 2
J 0
(-4340 3580);
DISPLAY 0.787234 (-4340 3580);
PAINT MONO (-4340 3580);
FORCEPROP 1 LAST PATH I165
J 0
(-4300 3850);
DISPLAY 0.978723 (-4300 3850);
PAINT WHITE (-4300 3850);
DISPLAY INVISIBLE (-4300 3850);
FORCEPROP 2 LAST CDS_LIB pure_quanta
J 0
(-4350 3700);
DISPLAY INVISIBLE (-4350 3700);
FORCEPROP 0 LAST $SEC 1
J 0
(-4400 3900);
DISPLAY 0.680851 (-4400 3900);
PAINT MONO (-4400 3900);
DISPLAY INVISIBLE (-4400 3900);
FORCEPROP 0 LAST CDS_SEC 1
J 0
(-4400 3900);
DISPLAY 1.021277 (-4400 3900);
DISPLAY INVISIBLE (-4400 3900);
FORCEADD Q_CAP..1
(-3475 3700);
FORCEPROP 1 LAST PART_NUMBER CH-8216TB09
J 0
(-3425 3600);
DISPLAY 0.510638 (-3425 3600);
DISPLAY INVISIBLE (-3425 3600);
FORCEPROP 1 LAST VALUE 8.2PF
J 0
(-3425 3800);
DISPLAY 0.510638 (-3425 3800);
FORCEPROP 1 LAST VOLTAGE 50V
J 0
(-3425 3750);
DISPLAY 0.510638 (-3425 3750);
FORCEPROP 1 LAST TOLERANCE 0.1P
J 0
(-3425 3700);
DISPLAY 0.510638 (-3425 3700);
FORCEPROP 1 LAST PACK_TYPE C0402
J 0
(-3425 3550);
DISPLAY 0.510638 (-3425 3550);
FORCEPROP 1 LAST MATERIAL NP0
J 0
(-3425 3650);
DISPLAY 0.510638 (-3425 3650);
FORCEPROP 1 LAST LOCATION C2256
J 0
(-3425 3850);
DISPLAY 0.510638 (-3425 3850);
FORCEPROP 1 LASTPIN (-3475 3800) $PN 1
J 0
(-3465 3780);
DISPLAY 0.787234 (-3465 3780);
PAINT MONO (-3465 3780);
FORCEPROP 1 LASTPIN (-3475 3600) $PN 2
J 0
(-3465 3580);
DISPLAY 0.787234 (-3465 3580);
PAINT MONO (-3465 3580);
FORCEPROP 1 LAST PATH I166
J 0
(-3425 3850);
DISPLAY 0.978723 (-3425 3850);
PAINT WHITE (-3425 3850);
DISPLAY INVISIBLE (-3425 3850);
FORCEPROP 2 LAST CDS_LIB pure_quanta
J 0
(-3475 3700);
DISPLAY INVISIBLE (-3475 3700);
FORCEPROP 0 LAST $SEC 1
J 0
(-3425 3875);
DISPLAY 0.680851 (-3425 3875);
PAINT MONO (-3425 3875);
DISPLAY INVISIBLE (-3425 3875);
FORCEPROP 0 LAST CDS_SEC 1
J 0
(-3425 3875);
DISPLAY 1.021277 (-3425 3875);
DISPLAY INVISIBLE (-3425 3875);
FORCEADD 9FGL0251DKILFT..1
(-1400 3500);
FORCEPROP 1 LAST PART_NUMBER AL000251002
J 0
(-1797 4344);
DISPLAY 0.723404 (-1797 4344);
PAINT GREEN (-1797 4344);
DISPLAY INVISIBLE (-1797 4344);
FORCEPROP 2 LAST VALUE 9FGL0251DKILFT
J 0
(-1775 4525);
DISPLAY 1.021277 (-1775 4525);
FORCEPROP 1 LAST MATERIAL IC
J 0
(-1797 4217);
DISPLAY 0.723404 (-1797 4217);
PAINT GREEN (-1797 4217);
FORCEPROP 2 LAST PART_TYPE SMLF
J 0
(-1775 4575);
DISPLAY 1.021277 (-1775 4575);
FORCEPROP 1 LAST LOCATION U247
J 0
(-1797 4491);
DISPLAY 0.723404 (-1797 4491);
PAINT GREEN (-1797 4491);
FORCEPROP 0 LASTPIN (-1950 3050) $PN 22
J 2
(-1960 3060);
DISPLAY 0.680851 (-1960 3060);
PAINT MONO (-1960 3060);
FORCEPROP 0 LASTPIN (-1950 2950) $PN 23
J 2
(-1960 2960);
DISPLAY 0.680851 (-1960 2960);
PAINT MONO (-1960 2960);
FORCEPROP 0 LASTPIN (-850 3750) $PN 13
J 0
(-840 3760);
DISPLAY 0.680851 (-840 3760);
PAINT MONO (-840 3760);
FORCEPROP 0 LASTPIN (-850 3700) $PN 14
J 0
(-840 3710);
DISPLAY 0.680851 (-840 3710);
PAINT MONO (-840 3710);
FORCEPROP 0 LASTPIN (-850 3600) $PN 17
J 0
(-840 3610);
DISPLAY 0.680851 (-840 3610);
PAINT MONO (-840 3610);
FORCEPROP 0 LASTPIN (-850 3550) $PN 18
J 0
(-840 3560);
DISPLAY 0.680851 (-840 3560);
PAINT MONO (-840 3560);
FORCEPROP 0 LASTPIN (-850 3050) $PN 10
J 0
(-840 3060);
DISPLAY 0.680851 (-840 3060);
PAINT MONO (-840 3060);
FORCEPROP 0 LASTPIN (-850 3000) $PN 21
J 0
(-840 3010);
DISPLAY 0.680851 (-840 3010);
PAINT MONO (-840 3010);
FORCEPROP 0 LASTPIN (-850 3100) $PN 15
J 0
(-840 3110);
DISPLAY 0.680851 (-840 3110);
PAINT MONO (-840 3110);
FORCEPROP 0 LASTPIN (-850 3150) $PN 6
J 0
(-840 3160);
DISPLAY 0.680851 (-840 3160);
PAINT MONO (-840 3160);
FORCEPROP 0 LASTPIN (-850 3200) $PN 5
J 0
(-840 3210);
DISPLAY 0.680851 (-840 3210);
PAINT MONO (-840 3210);
FORCEPROP 0 LASTPIN (-850 3250) $PN 24
J 0
(-840 3260);
DISPLAY 0.680851 (-840 3260);
PAINT MONO (-840 3260);
FORCEPROP 0 LASTPIN (-1950 3500) $PN 8
J 2
(-1960 3510);
DISPLAY 0.680851 (-1960 3510);
PAINT MONO (-1960 3510);
FORCEPROP 0 LASTPIN (-1950 3450) $PN 9
J 2
(-1960 3460);
DISPLAY 0.680851 (-1960 3460);
PAINT MONO (-1960 3460);
FORCEPROP 0 LASTPIN (-850 2850) $PN 25
J 0
(-840 2860);
DISPLAY 0.680851 (-840 2860);
PAINT MONO (-840 2860);
FORCEPROP 0 LASTPIN (-1950 4000) $PN 11
J 2
(-1960 4010);
DISPLAY 0.680851 (-1960 4010);
PAINT MONO (-1960 4010);
FORCEPROP 0 LASTPIN (-1950 4050) $PN 20
J 2
(-1960 4060);
DISPLAY 0.680851 (-1960 4060);
PAINT MONO (-1960 4060);
FORCEPROP 0 LASTPIN (-1950 4150) $PN 16
J 2
(-1960 4160);
DISPLAY 0.680851 (-1960 4160);
PAINT MONO (-1960 4160);
FORCEPROP 0 LASTPIN (-1950 4100) $PN 7
J 2
(-1960 4110);
DISPLAY 0.680851 (-1960 4110);
PAINT MONO (-1960 4110);
FORCEPROP 0 LASTPIN (-1950 3950) $PN 3
J 2
(-1960 3960);
DISPLAY 0.680851 (-1960 3960);
PAINT MONO (-1960 3960);
FORCEPROP 0 LASTPIN (-1950 3350) $PN 12
J 2
(-1960 3360);
DISPLAY 0.680851 (-1960 3360);
PAINT MONO (-1960 3360);
FORCEPROP 0 LASTPIN (-1950 3300) $PN 19
J 2
(-1960 3310);
DISPLAY 0.680851 (-1960 3310);
PAINT MONO (-1960 3310);
FORCEPROP 0 LASTPIN (-850 4150) $PN 4
J 0
(-840 4160);
DISPLAY 0.680851 (-840 4160);
PAINT MONO (-840 4160);
FORCEPROP 0 LASTPIN (-1950 3700) $PN 2
J 2
(-1960 3710);
DISPLAY 0.680851 (-1960 3710);
PAINT MONO (-1960 3710);
FORCEPROP 0 LASTPIN (-1950 3750) $PN 1
J 2
(-1960 3760);
DISPLAY 0.680851 (-1960 3760);
PAINT MONO (-1960 3760);
FORCEPROP 1 LAST NEEDS_NO_SIZE TRUE
J 0
(-1400 3500);
DISPLAY 0.723404 (-1400 3500);
PAINT GREEN (-1400 3500);
DISPLAY INVISIBLE (-1400 3500);
FORCEPROP 1 LAST CDS_LMAN_SYM_OUTLINE -400,700,400,-700
J 0
(-1400 3500);
DISPLAY 0.468085 (-1400 3500);
PAINT GREEN (-1400 3500);
DISPLAY INVISIBLE (-1400 3500);
FORCEPROP 1 LAST PATH I167
J 0
(-1400 3500);
DISPLAY 0.723404 (-1400 3500);
PAINT GREEN (-1400 3500);
DISPLAY INVISIBLE (-1400 3500);
FORCEPROP 2 LAST CDS_LIB pure_quanta
J 0
(-1400 3500);
DISPLAY INVISIBLE (-1400 3500);
FORCEPROP 0 LAST $SEC 1
J 0
(-1775 4625);
DISPLAY 0.680851 (-1775 4625);
PAINT MONO (-1775 4625);
DISPLAY INVISIBLE (-1775 4625);
FORCEPROP 0 LAST CDS_SEC 1
J 0
(-1775 4625);
DISPLAY 1.021277 (-1775 4625);
DISPLAY INVISIBLE (-1775 4625);
FORCEADD Q_CAP..1
(-2075 5000);
FORCEPROP 1 LAST PART_NUMBER CH4104K1B00
J 0
(-2025 4850);
DISPLAY 0.808511 (-2025 4850);
DISPLAY INVISIBLE (-2025 4850);
FORCEPROP 1 LAST VALUE 0.1UF
J 0
(-2025 5050);
DISPLAY 0.638298 (-2025 5050);
FORCEPROP 1 LAST VOLTAGE 25V
J 0
(-2025 5000);
DISPLAY 0.638298 (-2025 5000);
FORCEPROP 1 LAST TOLERANCE 10%
J 0
(-2025 4950);
DISPLAY 0.638298 (-2025 4950);
FORCEPROP 1 LAST PACK_TYPE 0402
J 0
(-2025 4850);
DISPLAY 0.638298 (-2025 4850);
FORCEPROP 1 LAST MATERIAL X7R
J 0
(-2025 4900);
DISPLAY 0.638298 (-2025 4900);
FORCEPROP 1 LAST $LOCATION C1886
J 0
(-2025 5100);
DISPLAY 0.638298 (-2025 5100);
FORCEPROP 1 LASTPIN (-2075 5100) $PN 1
J 0
(-2065 5080);
DISPLAY 0.787234 (-2065 5080);
PAINT MONO (-2065 5080);
FORCEPROP 1 LASTPIN (-2075 4900) $PN 2
J 0
(-2065 4880);
DISPLAY 0.787234 (-2065 4880);
PAINT MONO (-2065 4880);
FORCEPROP 1 LAST PATH I18
J 0
(-2025 5150);
DISPLAY 0.978723 (-2025 5150);
PAINT WHITE (-2025 5150);
DISPLAY INVISIBLE (-2025 5150);
FORCEPROP 2 LAST CDS_LIB pure_quanta
J 0
(-2075 5000);
DISPLAY INVISIBLE (-2075 5000);
FORCEPROP 0 LAST CDS_LOCATION C1886
J 0
(-2025 5150);
DISPLAY 1.021277 (-2025 5150);
DISPLAY INVISIBLE (-2025 5150);
FORCEPROP 0 LAST $SEC 1
J 0
(-2025 5150);
DISPLAY 0.680851 (-2025 5150);
PAINT MONO (-2025 5150);
DISPLAY INVISIBLE (-2025 5150);
FORCEPROP 0 LAST CDS_SEC 1
J 0
(-2025 5150);
DISPLAY 1.021277 (-2025 5150);
DISPLAY INVISIBLE (-2025 5150);
FORCEADD Q_CAP..1
(-1850 5000);
FORCEPROP 1 LAST PART_NUMBER CH4104K1B00
J 0
(-1800 4850);
DISPLAY 0.808511 (-1800 4850);
DISPLAY INVISIBLE (-1800 4850);
FORCEPROP 1 LAST VALUE 0.1UF
J 0
(-1800 5050);
DISPLAY 0.638298 (-1800 5050);
FORCEPROP 1 LAST VOLTAGE 25V
J 0
(-1800 5000);
DISPLAY 0.638298 (-1800 5000);
FORCEPROP 1 LAST TOLERANCE 10%
J 0
(-1800 4950);
DISPLAY 0.638298 (-1800 4950);
FORCEPROP 1 LAST MATERIAL X7R
J 0
(-1800 4900);
DISPLAY 0.638298 (-1800 4900);
FORCEPROP 1 LAST PACK_TYPE 0402
J 0
(-1800 4850);
DISPLAY 0.638298 (-1800 4850);
FORCEPROP 1 LAST $LOCATION C1889
J 0
(-1800 5100);
DISPLAY 0.638298 (-1800 5100);
FORCEPROP 1 LASTPIN (-1850 5100) $PN 1
J 0
(-1840 5080);
DISPLAY 0.787234 (-1840 5080);
PAINT MONO (-1840 5080);
FORCEPROP 1 LASTPIN (-1850 4900) $PN 2
J 0
(-1840 4880);
DISPLAY 0.787234 (-1840 4880);
PAINT MONO (-1840 4880);
FORCEPROP 1 LAST PATH I19
J 0
(-1800 5150);
DISPLAY 0.978723 (-1800 5150);
PAINT WHITE (-1800 5150);
DISPLAY INVISIBLE (-1800 5150);
FORCEPROP 2 LAST CDS_LIB pure_quanta
J 0
(-1850 5000);
DISPLAY INVISIBLE (-1850 5000);
FORCEPROP 0 LAST CDS_LOCATION C1889
J 0
(-1800 5150);
DISPLAY 1.021277 (-1800 5150);
DISPLAY INVISIBLE (-1800 5150);
FORCEPROP 0 LAST $SEC 1
J 0
(-1800 5150);
DISPLAY 0.680851 (-1800 5150);
PAINT MONO (-1800 5150);
DISPLAY INVISIBLE (-1800 5150);
FORCEPROP 0 LAST CDS_SEC 1
J 0
(-1800 5150);
DISPLAY 1.021277 (-1800 5150);
DISPLAY INVISIBLE (-1800 5150);
FORCEADD UNIVERSAL_POWER..1
(-3500 5325);
FORCEPROP 3 LASTPIN (-3500 5275) SIG_NAME P3V3_AUX\g
J 0
(-3490 5285);
DISPLAY 0.659574 (-3490 5285);
PAINT MONO (-3490 5285);
DISPLAY INVISIBLE (-3490 5285);
FORCEPROP 1 LAST HDL_POWER P3V3_AUX
J 1
(-3500 5375);
DISPLAY 0.872340 (-3500 5375);
PAINT GREEN (-3500 5375);
FORCEPROP 2 LAST CDS_LIB logical_power
J 0
(-3500 5325);
DISPLAY INVISIBLE (-3500 5325);
FORCEPROP 1 LAST PATH I20
J 0
(-3450 5350);
DISPLAY 0.872340 (-3450 5350);
PAINT AQUA (-3450 5350);
DISPLAY INVISIBLE (-3450 5350);
FORCEADD UNIVERSAL_GND..1
(-1600 4650);
FORCEPROP 3 LASTPIN (-1600 4700) SIG_NAME GND\g
J 0
(-1590 4710);
DISPLAY 0.659574 (-1590 4710);
PAINT MONO (-1590 4710);
DISPLAY INVISIBLE (-1590 4710);
FORCEPROP 2 LAST CDS_LIB logical_power
J 0
(-1600 4650);
DISPLAY INVISIBLE (-1600 4650);
FORCEPROP 1 LAST PATH I21
J 0
(-1525 4650);
DISPLAY 0.872340 (-1525 4650);
PAINT AQUA (-1525 4650);
DISPLAY INVISIBLE (-1525 4650);
FORCEPROP 1 LAST HDL_POWER GND
J 1
(-1575 4575);
DISPLAY 0.872340 (-1575 4575);
PAINT GREEN (-1575 4575);
DISPLAY INVISIBLE (-1575 4575);
FORCEADD UNIVERSAL_GND..1
(-700 2500);
FORCEPROP 3 LASTPIN (-700 2550) SIG_NAME GND\g
J 0
(-690 2560);
DISPLAY 0.659574 (-690 2560);
PAINT MONO (-690 2560);
DISPLAY INVISIBLE (-690 2560);
FORCEPROP 1 LAST HDL_POWER GND
J 1
(-675 2425);
DISPLAY 0.872340 (-675 2425);
PAINT GREEN (-675 2425);
DISPLAY INVISIBLE (-675 2425);
FORCEPROP 1 LAST PATH I22
J 0
(-625 2500);
DISPLAY 0.872340 (-625 2500);
PAINT AQUA (-625 2500);
DISPLAY INVISIBLE (-625 2500);
FORCEPROP 2 LAST CDS_LIB logical_power
J 0
(-700 2500);
DISPLAY INVISIBLE (-700 2500);
FORCEADD OFFPAGE..2
(950 1225);
FORCEPROP 2 LAST $XR0 212 
J 0
(1139 1225);
DISPLAY 0.638298 (1139 1225);
PAINT MONO (1139 1225);
FORCEPROP 2 LAST CDS_LIB standard
J 0
(950 1225);
DISPLAY INVISIBLE (950 1225);
FORCEPROP 2 LAST PATH I32
J 0
(1125 1300);
DISPLAY 1.021277 (1125 1300);
DISPLAY INVISIBLE (1125 1300);
FORCEPROP 1 LAST COMMENT_BODY TRUE
J 0
(905 1130);
DISPLAY 0.872340 (905 1130);
PAINT GREEN (905 1130);
DISPLAY INVISIBLE (905 1130);
FORCEPROP 1 LAST OFFPAGE TRUE
J 0
(1275 1100);
DISPLAY 0.872340 (1275 1100);
DISPLAY INVISIBLE (1275 1100);
FORCEADD UNIVERSAL_POWER..1
(250 1750);
FORCEPROP 3 LASTPIN (250 1700) SIG_NAME P3V3_AUX\g
J 0
(260 1710);
DISPLAY 0.659574 (260 1710);
PAINT MONO (260 1710);
DISPLAY INVISIBLE (260 1710);
FORCEPROP 1 LAST HDL_POWER P3V3_AUX
J 1
(250 1800);
DISPLAY 0.872340 (250 1800);
PAINT GREEN (250 1800);
FORCEPROP 2 LAST CDS_LIB logical_power
J 0
(250 1750);
DISPLAY INVISIBLE (250 1750);
FORCEPROP 1 LAST PATH I33
J 0
(300 1775);
DISPLAY 0.872340 (300 1775);
PAINT AQUA (300 1775);
DISPLAY INVISIBLE (300 1775);
FORCEADD UNIVERSAL_GND..1
(250 725);
FORCEPROP 3 LASTPIN (250 775) SIG_NAME GND\g
J 0
(260 785);
DISPLAY 0.659574 (260 785);
PAINT MONO (260 785);
DISPLAY INVISIBLE (260 785);
FORCEPROP 1 LAST HDL_POWER GND
J 1
(275 650);
DISPLAY 0.872340 (275 650);
PAINT GREEN (275 650);
DISPLAY INVISIBLE (275 650);
FORCEPROP 2 LAST CDS_LIB logical_power
J 0
(250 725);
DISPLAY INVISIBLE (250 725);
FORCEPROP 1 LAST PATH I35
J 0
(325 725);
DISPLAY 0.872340 (325 725);
PAINT AQUA (325 725);
DISPLAY INVISIBLE (325 725);
FORCEADD Q_RES..1
(175 3750);
FORCEPROP 1 LAST PART_NUMBER CS00002JB13
J 0
(300 3800);
DISPLAY 0.638298 (300 3800);
DISPLAY INVISIBLE (300 3800);
FORCEPROP 1 LAST VALUE 0
J 2
(325 3750);
DISPLAY 0.787234 (325 3750);
FORCEPROP 1 LAST MATERIAL CHIP
J 0
(350 3750);
DISPLAY 0.638298 (350 3750);
FORCEPROP 1 LAST $LOCATION R3335
J 0
(-50 3750);
DISPLAY 0.638298 (-50 3750);
FORCEPROP 1 LASTPIN (75 3750) $PN 1
J 0
(87 3762);
DISPLAY 0.787234 (87 3762);
PAINT MONO (87 3762);
FORCEPROP 1 LASTPIN (275 3750) $PN 2
J 0
(237 3762);
DISPLAY 0.787234 (237 3762);
PAINT MONO (237 3762);
FORCEPROP 1 LAST PACK_TYPE 0402LF
J 0
(575 3750);
DISPLAY 0.638298 (575 3750);
DISPLAY INVISIBLE (575 3750);
FORCEPROP 1 LAST TOLERANCE 5%
J 0
(475 3750);
DISPLAY 0.638298 (475 3750);
DISPLAY INVISIBLE (475 3750);
FORCEPROP 1 LAST WATTAGE 1/16W
J 2
(650 3850);
DISPLAY 0.638298 (650 3850);
DISPLAY INVISIBLE (650 3850);
FORCEPROP 1 LAST PATH I69
J 0
(125 3900);
DISPLAY 0.978723 (125 3900);
PAINT WHITE (125 3900);
DISPLAY INVISIBLE (125 3900);
FORCEPROP 2 LAST CDS_LIB pure_quanta
J 0
(175 3750);
DISPLAY INVISIBLE (175 3750);
FORCEPROP 0 LAST CDS_LOCATION R3335
J 0
(125 3850);
DISPLAY 1.021277 (125 3850);
DISPLAY INVISIBLE (125 3850);
FORCEPROP 0 LAST $SEC 1
J 0
(125 3850);
DISPLAY 0.680851 (125 3850);
PAINT MONO (125 3850);
DISPLAY INVISIBLE (125 3850);
FORCEPROP 0 LAST CDS_SEC 1
J 0
(125 3850);
DISPLAY 1.021277 (125 3850);
DISPLAY INVISIBLE (125 3850);
FORCEADD OFFPAGE..2
(1250 3750);
FORCEPROP 2 LAST $XR0 240 
J 0
(1439 3750);
DISPLAY 0.638298 (1439 3750);
PAINT MONO (1439 3750);
FORCEPROP 2 LAST PATH I70
J 0
(1425 3825);
DISPLAY 1.021277 (1425 3825);
DISPLAY INVISIBLE (1425 3825);
FORCEPROP 2 LAST CDS_LIB standard
J 0
(1250 3750);
DISPLAY INVISIBLE (1250 3750);
FORCEPROP 1 LAST OFFPAGE TRUE
J 0
(1575 3625);
DISPLAY 0.872340 (1575 3625);
DISPLAY INVISIBLE (1575 3625);
FORCEPROP 1 LAST COMMENT_BODY TRUE
J 0
(1205 3655);
DISPLAY 0.872340 (1205 3655);
PAINT GREEN (1205 3655);
DISPLAY INVISIBLE (1205 3655);
FORCEADD OFFPAGE..2
(1250 3700);
FORCEPROP 2 LAST $XR0 240 
J 0
(1439 3700);
DISPLAY 0.638298 (1439 3700);
PAINT MONO (1439 3700);
FORCEPROP 2 LAST PATH I71
J 0
(1425 3775);
DISPLAY 1.021277 (1425 3775);
DISPLAY INVISIBLE (1425 3775);
FORCEPROP 2 LAST CDS_LIB standard
J 0
(1250 3700);
DISPLAY INVISIBLE (1250 3700);
FORCEPROP 1 LAST COMMENT_BODY TRUE
J 0
(1205 3605);
DISPLAY 0.872340 (1205 3605);
PAINT GREEN (1205 3605);
DISPLAY INVISIBLE (1205 3605);
FORCEPROP 1 LAST OFFPAGE TRUE
J 0
(1575 3575);
DISPLAY 0.872340 (1575 3575);
DISPLAY INVISIBLE (1575 3575);
FORCEADD OFFPAGE..2
(1250 3550);
FORCEPROP 2 LAST $XR0 143 
J 0
(1439 3550);
DISPLAY 0.638298 (1439 3550);
PAINT MONO (1439 3550);
FORCEPROP 2 LAST PATH I72
J 0
(1425 3625);
DISPLAY 1.021277 (1425 3625);
DISPLAY INVISIBLE (1425 3625);
FORCEPROP 1 LAST OFFPAGE TRUE
J 0
(1575 3425);
DISPLAY 0.872340 (1575 3425);
DISPLAY INVISIBLE (1575 3425);
FORCEPROP 1 LAST COMMENT_BODY TRUE
J 0
(1205 3455);
DISPLAY 0.872340 (1205 3455);
PAINT GREEN (1205 3455);
DISPLAY INVISIBLE (1205 3455);
FORCEPROP 2 LAST CDS_LIB standard
J 0
(1250 3550);
DISPLAY INVISIBLE (1250 3550);
FORCEADD OFFPAGE..2
(1250 3600);
FORCEPROP 2 LAST $XR0 143 
J 0
(1439 3600);
DISPLAY 0.638298 (1439 3600);
PAINT MONO (1439 3600);
FORCEPROP 2 LAST PATH I73
J 0
(1425 3675);
DISPLAY 1.021277 (1425 3675);
DISPLAY INVISIBLE (1425 3675);
FORCEPROP 1 LAST COMMENT_BODY TRUE
J 0
(1205 3505);
DISPLAY 0.872340 (1205 3505);
PAINT GREEN (1205 3505);
DISPLAY INVISIBLE (1205 3505);
FORCEPROP 1 LAST OFFPAGE TRUE
J 0
(1575 3475);
DISPLAY 0.872340 (1575 3475);
DISPLAY INVISIBLE (1575 3475);
FORCEPROP 2 LAST CDS_LIB standard
J 0
(1250 3600);
DISPLAY INVISIBLE (1250 3600);
FORCEADD Q_RES..1
(175 3700);
FORCEPROP 1 LAST PART_NUMBER CS00002JB13
J 0
(300 3750);
DISPLAY 0.638298 (300 3750);
DISPLAY INVISIBLE (300 3750);
FORCEPROP 1 LAST VALUE 0
J 2
(325 3700);
DISPLAY 0.787234 (325 3700);
FORCEPROP 1 LAST MATERIAL CHIP
J 0
(350 3700);
DISPLAY 0.638298 (350 3700);
FORCEPROP 1 LAST $LOCATION R3336
J 0
(-50 3700);
DISPLAY 0.638298 (-50 3700);
FORCEPROP 1 LASTPIN (75 3700) $PN 1
J 0
(87 3712);
DISPLAY 0.787234 (87 3712);
PAINT MONO (87 3712);
FORCEPROP 1 LASTPIN (275 3700) $PN 2
J 0
(237 3712);
DISPLAY 0.787234 (237 3712);
PAINT MONO (237 3712);
FORCEPROP 2 LAST CDS_LIB pure_quanta
J 0
(175 3700);
DISPLAY INVISIBLE (175 3700);
FORCEPROP 1 LAST PATH I74
J 0
(125 3850);
DISPLAY 0.978723 (125 3850);
PAINT WHITE (125 3850);
DISPLAY INVISIBLE (125 3850);
FORCEPROP 1 LAST PACK_TYPE 0402LF
J 0
(575 3700);
DISPLAY 0.638298 (575 3700);
DISPLAY INVISIBLE (575 3700);
FORCEPROP 1 LAST TOLERANCE 5%
J 0
(475 3700);
DISPLAY 0.638298 (475 3700);
DISPLAY INVISIBLE (475 3700);
FORCEPROP 1 LAST WATTAGE 1/16W
J 2
(650 3800);
DISPLAY 0.638298 (650 3800);
DISPLAY INVISIBLE (650 3800);
FORCEPROP 0 LAST CDS_LOCATION R3336
J 0
(125 3800);
DISPLAY 1.021277 (125 3800);
DISPLAY INVISIBLE (125 3800);
FORCEPROP 0 LAST $SEC 1
J 0
(125 3800);
DISPLAY 0.680851 (125 3800);
PAINT MONO (125 3800);
DISPLAY INVISIBLE (125 3800);
FORCEPROP 0 LAST CDS_SEC 1
J 0
(125 3800);
DISPLAY 1.021277 (125 3800);
DISPLAY INVISIBLE (125 3800);
FORCEADD Q_RES..1
(175 3600);
FORCEPROP 1 LAST PART_NUMBER CS00002JB13
J 0
(300 3650);
DISPLAY 0.638298 (300 3650);
DISPLAY INVISIBLE (300 3650);
FORCEPROP 1 LAST MATERIAL CHIP
J 0
(350 3600);
DISPLAY 0.638298 (350 3600);
FORCEPROP 1 LAST VALUE 0
J 2
(325 3600);
DISPLAY 0.787234 (325 3600);
FORCEPROP 1 LAST $LOCATION R3337
J 0
(-50 3600);
DISPLAY 0.638298 (-50 3600);
FORCEPROP 1 LASTPIN (75 3600) $PN 1
J 0
(87 3612);
DISPLAY 0.787234 (87 3612);
PAINT MONO (87 3612);
FORCEPROP 1 LASTPIN (275 3600) $PN 2
J 0
(237 3612);
DISPLAY 0.787234 (237 3612);
PAINT MONO (237 3612);
FORCEPROP 2 LAST CDS_LIB pure_quanta
J 0
(175 3600);
DISPLAY INVISIBLE (175 3600);
FORCEPROP 1 LAST PATH I75
J 0
(125 3750);
DISPLAY 0.978723 (125 3750);
PAINT WHITE (125 3750);
DISPLAY INVISIBLE (125 3750);
FORCEPROP 1 LAST WATTAGE 1/16W
J 2
(650 3700);
DISPLAY 0.638298 (650 3700);
DISPLAY INVISIBLE (650 3700);
FORCEPROP 1 LAST TOLERANCE 5%
J 0
(475 3600);
DISPLAY 0.638298 (475 3600);
DISPLAY INVISIBLE (475 3600);
FORCEPROP 1 LAST PACK_TYPE 0402LF
J 0
(575 3600);
DISPLAY 0.638298 (575 3600);
DISPLAY INVISIBLE (575 3600);
FORCEPROP 0 LAST CDS_LOCATION R3337
J 0
(125 3700);
DISPLAY 1.021277 (125 3700);
DISPLAY INVISIBLE (125 3700);
FORCEPROP 0 LAST $SEC 1
J 0
(125 3700);
DISPLAY 0.680851 (125 3700);
PAINT MONO (125 3700);
DISPLAY INVISIBLE (125 3700);
FORCEPROP 0 LAST CDS_SEC 1
J 0
(125 3700);
DISPLAY 1.021277 (125 3700);
DISPLAY INVISIBLE (125 3700);
FORCEADD Q_RES..1
(175 3550);
FORCEPROP 1 LAST PART_NUMBER CS00002JB13
J 0
(25 3475);
DISPLAY 0.638298 (25 3475);
DISPLAY INVISIBLE (25 3475);
FORCEPROP 1 LAST VALUE 0
J 2
(325 3550);
DISPLAY 0.787234 (325 3550);
FORCEPROP 1 LAST TOLERANCE 5%
J 0
(250 3425);
DISPLAY 0.638298 (250 3425);
FORCEPROP 1 LAST MATERIAL CHIP
J 0
(350 3550);
DISPLAY 0.638298 (350 3550);
FORCEPROP 1 LAST PACK_TYPE 0402LF
J 0
(50 3425);
DISPLAY 0.638298 (50 3425);
FORCEPROP 1 LAST WATTAGE 1/16W
J 2
(250 3375);
DISPLAY 0.638298 (250 3375);
FORCEPROP 1 LAST $LOCATION R3338
J 0
(-50 3550);
DISPLAY 0.638298 (-50 3550);
FORCEPROP 1 LASTPIN (75 3550) $PN 1
J 0
(87 3562);
DISPLAY 0.787234 (87 3562);
PAINT MONO (87 3562);
FORCEPROP 1 LASTPIN (275 3550) $PN 2
J 0
(237 3562);
DISPLAY 0.787234 (237 3562);
PAINT MONO (237 3562);
FORCEPROP 2 LAST CDS_LIB pure_quanta
J 0
(175 3550);
DISPLAY INVISIBLE (175 3550);
FORCEPROP 1 LAST PATH I76
J 0
(125 3700);
DISPLAY 0.978723 (125 3700);
PAINT WHITE (125 3700);
DISPLAY INVISIBLE (125 3700);
FORCEPROP 0 LAST CDS_LOCATION R3338
J 0
(125 3650);
DISPLAY 1.021277 (125 3650);
DISPLAY INVISIBLE (125 3650);
FORCEPROP 0 LAST $SEC 1
J 0
(125 3650);
DISPLAY 0.680851 (125 3650);
PAINT MONO (125 3650);
DISPLAY INVISIBLE (125 3650);
FORCEPROP 0 LAST CDS_SEC 1
J 0
(125 3650);
DISPLAY 1.021277 (125 3650);
DISPLAY INVISIBLE (125 3650);
FORCEADD UNIVERSAL_POWER..1
(-2375 2350);
FORCEPROP 3 LASTPIN (-2375 2300) SIG_NAME P3V3_AUX\g
J 0
(-2365 2310);
DISPLAY 0.659574 (-2365 2310);
PAINT MONO (-2365 2310);
DISPLAY INVISIBLE (-2365 2310);
FORCEPROP 1 LAST HDL_POWER P3V3_AUX
J 1
(-2375 2400);
DISPLAY 0.872340 (-2375 2400);
PAINT GREEN (-2375 2400);
FORCEPROP 1 LAST PATH I79
J 0
(-2325 2375);
DISPLAY 0.872340 (-2325 2375);
PAINT AQUA (-2325 2375);
DISPLAY INVISIBLE (-2325 2375);
FORCEPROP 2 LAST CDS_LIB logical_power
J 0
(-2375 2350);
PAINT MONO (-2375 2350);
DISPLAY INVISIBLE (-2375 2350);
FORCEADD Q_CAP..1
(-2375 1925);
FORCEPROP 1 LAST PART_NUMBER CH4104K1B00
J 0
(-2325 1775);
DISPLAY 0.510638 (-2325 1775);
DISPLAY INVISIBLE (-2325 1775);
FORCEPROP 1 LAST VOLTAGE 25V
J 0
(-2325 1925);
DISPLAY 0.510638 (-2325 1925);
FORCEPROP 1 LAST VALUE 0.1UF
J 0
(-2325 1975);
DISPLAY 0.510638 (-2325 1975);
FORCEPROP 1 LAST MATERIAL X7R
J 0
(-2325 1825);
DISPLAY 0.510638 (-2325 1825);
FORCEPROP 1 LAST TOLERANCE 10%
J 0
(-2325 1875);
DISPLAY 0.510638 (-2325 1875);
FORCEPROP 1 LAST PACK_TYPE 0402
J 0
(-2325 1725);
DISPLAY 0.510638 (-2325 1725);
FORCEPROP 1 LAST $LOCATION C1882
J 0
(-2325 2025);
DISPLAY 0.638298 (-2325 2025);
FORCEPROP 1 LASTPIN (-2375 2025) $PN 1
J 0
(-2365 2005);
DISPLAY 0.787234 (-2365 2005);
FORCEPROP 1 LASTPIN (-2375 1825) $PN 2
J 0
(-2365 1805);
DISPLAY 0.787234 (-2365 1805);
FORCEPROP 2 LAST CDS_LIB pure_quanta
J 0
(-2375 1925);
PAINT MONO (-2375 1925);
DISPLAY INVISIBLE (-2375 1925);
FORCEPROP 1 LAST PATH I80
J 0
(-2325 2075);
DISPLAY 0.978723 (-2325 2075);
PAINT WHITE (-2325 2075);
DISPLAY INVISIBLE (-2325 2075);
FORCEPROP 2 LAST CDS_LOCATION C1882
J 0
(-2325 2125);
DISPLAY 1.021277 (-2325 2125);
DISPLAY INVISIBLE (-2325 2125);
FORCEPROP 2 LAST $SEC 1
J 2
(-2325 2125);
DISPLAY 0.680851 (-2325 2125);
PAINT MONO (-2325 2125);
DISPLAY INVISIBLE (-2325 2125);
FORCEPROP 2 LAST CDS_SEC 1
J 2
(-2325 2125);
DISPLAY 1.021277 (-2325 2125);
DISPLAY INVISIBLE (-2325 2125);
FORCEADD UNIVERSAL_GND..1
(-2375 1675);
FORCEPROP 3 LASTPIN (-2375 1725) SIG_NAME GND\g
J 0
(-2365 1735);
DISPLAY 0.659574 (-2365 1735);
PAINT MONO (-2365 1735);
DISPLAY INVISIBLE (-2365 1735);
FORCEPROP 1 LAST PATH I81
J 0
(-2300 1675);
DISPLAY 0.872340 (-2300 1675);
PAINT AQUA (-2300 1675);
DISPLAY INVISIBLE (-2300 1675);
FORCEPROP 2 LAST CDS_LIB logical_power
J 0
(-2375 1675);
PAINT MONO (-2375 1675);
DISPLAY INVISIBLE (-2375 1675);
FORCEPROP 1 LAST HDL_POWER GND
J 1
(-2350 1600);
DISPLAY 0.872340 (-2350 1600);
PAINT GREEN (-2350 1600);
DISPLAY INVISIBLE (-2350 1600);
FORCEADD UNIVERSAL_GND..1
(-2550 975);
FORCEPROP 3 LASTPIN (-2550 1025) SIG_NAME GND\g
J 0
(-2540 1035);
DISPLAY 0.659574 (-2540 1035);
PAINT MONO (-2540 1035);
DISPLAY INVISIBLE (-2540 1035);
FORCEPROP 1 LAST HDL_POWER GND
J 1
(-2525 900);
DISPLAY 0.872340 (-2525 900);
PAINT GREEN (-2525 900);
DISPLAY INVISIBLE (-2525 900);
FORCEPROP 1 LAST PATH I82
J 0
(-2475 975);
DISPLAY 0.872340 (-2475 975);
PAINT AQUA (-2475 975);
DISPLAY INVISIBLE (-2475 975);
FORCEPROP 2 LAST CDS_LIB logical_power
J 0
(-2550 975);
DISPLAY INVISIBLE (-2550 975);
FORCEADD Q_RES..1
(-3725 1300);
FORCEPROP 1 LAST PART_NUMBER CS00002JB13
J 0
(-3600 1350);
DISPLAY 0.638298 (-3600 1350);
DISPLAY INVISIBLE (-3600 1350);
FORCEPROP 1 LAST MATERIAL CHIP
J 0
(-3550 1300);
DISPLAY 0.638298 (-3550 1300);
FORCEPROP 1 LAST VALUE 0
J 2
(-3575 1300);
DISPLAY 0.787234 (-3575 1300);
FORCEPROP 1 LAST $LOCATION R3326
J 0
(-3950 1300);
DISPLAY 0.638298 (-3950 1300);
FORCEPROP 1 LASTPIN (-3825 1300) $PN 1
J 0
(-3813 1312);
DISPLAY 0.787234 (-3813 1312);
PAINT MONO (-3813 1312);
FORCEPROP 1 LASTPIN (-3625 1300) $PN 2
J 0
(-3663 1312);
DISPLAY 0.787234 (-3663 1312);
PAINT MONO (-3663 1312);
FORCEPROP 1 LAST WATTAGE 1/16W
J 2
(-3250 1400);
DISPLAY 0.638298 (-3250 1400);
DISPLAY INVISIBLE (-3250 1400);
FORCEPROP 1 LAST TOLERANCE 5%
J 0
(-3425 1300);
DISPLAY 0.638298 (-3425 1300);
DISPLAY INVISIBLE (-3425 1300);
FORCEPROP 1 LAST PACK_TYPE 0402LF
J 0
(-3325 1300);
DISPLAY 0.638298 (-3325 1300);
DISPLAY INVISIBLE (-3325 1300);
FORCEPROP 2 LAST CDS_LIB pure_quanta
J 0
(-3725 1300);
DISPLAY INVISIBLE (-3725 1300);
FORCEPROP 1 LAST PATH I84
J 0
(-3775 1450);
DISPLAY 0.978723 (-3775 1450);
PAINT WHITE (-3775 1450);
DISPLAY INVISIBLE (-3775 1450);
FORCEPROP 0 LAST CDS_LOCATION R3326
J 0
(-3550 1350);
DISPLAY 1.021277 (-3550 1350);
DISPLAY INVISIBLE (-3550 1350);
FORCEPROP 0 LAST $SEC 1
J 0
(-3550 1350);
DISPLAY 0.680851 (-3550 1350);
PAINT MONO (-3550 1350);
DISPLAY INVISIBLE (-3550 1350);
FORCEPROP 0 LAST CDS_SEC 1
J 0
(-3550 1350);
DISPLAY 1.021277 (-3550 1350);
DISPLAY INVISIBLE (-3550 1350);
FORCEADD Q_RES..1
(-3725 1200);
FORCEPROP 1 LAST PART_NUMBER CS00002JB13
J 0
(-3875 1125);
DISPLAY 0.638298 (-3875 1125);
DISPLAY INVISIBLE (-3875 1125);
FORCEPROP 1 LAST WATTAGE 1/16W
J 2
(-3650 1025);
DISPLAY 0.638298 (-3650 1025);
FORCEPROP 1 LAST TOLERANCE 5%
J 0
(-3650 1075);
DISPLAY 0.638298 (-3650 1075);
FORCEPROP 1 LAST MATERIAL CHIP
J 0
(-3550 1200);
DISPLAY 0.638298 (-3550 1200);
FORCEPROP 1 LAST PACK_TYPE 0402LF
J 0
(-3850 1075);
DISPLAY 0.638298 (-3850 1075);
FORCEPROP 1 LAST VALUE 0
J 2
(-3575 1200);
DISPLAY 0.787234 (-3575 1200);
FORCEPROP 1 LAST $LOCATION R3327
J 0
(-3950 1200);
DISPLAY 0.638298 (-3950 1200);
FORCEPROP 1 LASTPIN (-3825 1200) $PN 1
J 0
(-3813 1212);
DISPLAY 0.787234 (-3813 1212);
PAINT MONO (-3813 1212);
FORCEPROP 1 LASTPIN (-3625 1200) $PN 2
J 0
(-3663 1212);
DISPLAY 0.787234 (-3663 1212);
PAINT MONO (-3663 1212);
FORCEPROP 2 LAST CDS_LIB pure_quanta
J 0
(-3725 1200);
DISPLAY INVISIBLE (-3725 1200);
FORCEPROP 1 LAST PATH I85
J 0
(-3775 1350);
DISPLAY 0.978723 (-3775 1350);
PAINT WHITE (-3775 1350);
DISPLAY INVISIBLE (-3775 1350);
FORCEPROP 0 LAST CDS_LOCATION R3327
J 0
(-3550 1250);
DISPLAY 1.021277 (-3550 1250);
DISPLAY INVISIBLE (-3550 1250);
FORCEPROP 0 LAST $SEC 1
J 0
(-3550 1250);
DISPLAY 0.680851 (-3550 1250);
PAINT MONO (-3550 1250);
DISPLAY INVISIBLE (-3550 1250);
FORCEPROP 0 LAST CDS_SEC 1
J 0
(-3550 1250);
DISPLAY 1.021277 (-3550 1250);
DISPLAY INVISIBLE (-3550 1250);
FORCEADD OFFPAGE..1
(-4775 1200);
FORCEPROP 2 LAST $XR0 214 
J 0
(-5057 1200);
DISPLAY 0.638298 (-5057 1200);
PAINT MONO (-5057 1200);
FORCEPROP 2 LAST CDS_LIB standard
J 0
(-4775 1200);
DISPLAY INVISIBLE (-4775 1200);
FORCEPROP 1 LAST OFFPAGE TRUE
J 0
(-4450 1075);
DISPLAY 0.872340 (-4450 1075);
PAINT GREEN (-4450 1075);
DISPLAY INVISIBLE (-4450 1075);
FORCEPROP 1 LAST COMMENT_BODY TRUE
J 0
(-4650 1100);
DISPLAY 0.872340 (-4650 1100);
PAINT GREEN (-4650 1100);
DISPLAY INVISIBLE (-4650 1100);
FORCEPROP 2 LAST PATH I87
J 0
(-5025 1250);
DISPLAY 1.021277 (-5025 1250);
DISPLAY INVISIBLE (-5025 1250);
FORCEADD OFFPAGE..1
(-4775 1300);
FORCEPROP 2 LAST $XR0 148 
J 0
(-5057 1300);
DISPLAY 0.638298 (-5057 1300);
PAINT MONO (-5057 1300);
FORCEPROP 1 LAST COMMENT_BODY TRUE
J 0
(-4650 1200);
DISPLAY 0.872340 (-4650 1200);
PAINT GREEN (-4650 1200);
DISPLAY INVISIBLE (-4650 1200);
FORCEPROP 1 LAST OFFPAGE TRUE
J 0
(-4450 1175);
DISPLAY 0.872340 (-4450 1175);
PAINT GREEN (-4450 1175);
DISPLAY INVISIBLE (-4450 1175);
FORCEPROP 2 LAST CDS_LIB standard
J 0
(-4775 1300);
DISPLAY INVISIBLE (-4775 1300);
FORCEPROP 2 LAST PATH I88
J 0
(-5025 1350);
DISPLAY 1.021277 (-5025 1350);
DISPLAY INVISIBLE (-5025 1350);
FORCEADD DESIGN_NOTE..1
(-2475 5725);
FORCEPROP 0 LAST S1 PLACE CLOSE TO U247 ALL VDD PINS
J 0
(-2625 5575);
DISPLAY 1.021277 (-2625 5575);
PAINT SKYBLUE (-2625 5575);
FORCEPROP 2 LAST CDS_LIB logical_power
J 0
(-2475 5725);
DISPLAY INVISIBLE (-2475 5725);
FORCEPROP 1 LAST COMMENT_BODY TRUE
J 0
(-2450 5825);
DISPLAY 0.978723 (-2450 5825);
DISPLAY INVISIBLE (-2450 5825);
FORCEADD DNS..2
(250 1450);
PAINT RED (250 1450);
FORCEPROP 2 LAST CDS_LIB mstr_misc
J 0
(250 1450);
DISPLAY INVISIBLE (250 1450);
FORCEPROP 1 LAST COMMENT_BODY TRUE
J 0
(250 1450);
DISPLAY INVISIBLE (250 1450);
FORCEADD DNS..2
(1575 1000);
PAINT RED (1575 1000);
FORCEPROP 1 LAST COMMENT_BODY TRUE
J 0
(1575 1000);
DISPLAY INVISIBLE (1575 1000);
FORCEPROP 2 LAST CDS_LIB mstr_misc
J 0
(1575 1000);
DISPLAY INVISIBLE (1575 1000);
FORCEADD DNS..2
(-3400 950);
PAINT RED (-3400 950);
FORCEPROP 2 LAST CDS_LIB mstr_misc
J 0
(-3400 950);
DISPLAY INVISIBLE (-3400 950);
FORCEPROP 1 LAST COMMENT_BODY TRUE
J 0
(-3400 950);
DISPLAY INVISIBLE (-3400 950);
FORCEADD QUANTA_TITLE_BLOCK_C..1
(3050 -700);
FORCEPROP 0 LAST CDS_CON_LAST_MODIFIED Fri Aug 25 14:03:29 2023
J 0
(1165 -685);
DISPLAY INVISIBLE (1165 -685);
FORCEPROP 1 LAST CUSTOM_TXT_CDS <CON_LAST_MODIFIED>
J 0
(1165 -685);
DISPLAY 0.978723 (1165 -685);
FORCEPROP 2 LAST CUSTOM_TXT_CDS <XR_PAGE_TITLE>
J 0
(-4840 4550);
DISPLAY 0.638298 (-4840 4550);
PAINT PINK (-4840 4550);
DISPLAY INVISIBLE (-4840 4550);
FORCEPROP 1 LAST CUSTOM_TXT_CDS <NAME_2>
J 0
(-125 -650);
FORCEPROP 1 LAST CUSTOM_TXT_CDS <NAME_1>
J 0
(-125 -525);
FORCEPROP 1 LAST CUSTOM_TXT_CDS <Q_NUMBER>
J 0
(1647 -597);
DISPLAY 1.212766 (1647 -597);
FORCEPROP 1 LAST CUSTOM_TXT_CDS <Q_PROJ>
J 0
(668 -598);
DISPLAY 1.212766 (668 -598);
FORCEPROP 1 LAST CUSTOM_TXT_CDS <Q_REV>
J 0
(2866 -597);
DISPLAY 1.212766 (2866 -597);
FORCEPROP 1 LAST CUSTOM_TXT_CDS <CON_PAGE_NUM> OF <CON_TOTAL_PAGES>
J 0
(2604 -682);
DISPLAY 0.978723 (2604 -682);
FORCEPROP 1 LAST Q_TITLE CLK-GEN(NON SSC)
J 0
(-6316 -674);
DISPLAY 2.446809 (-6316 -674);
PAINT GREEN (-6316 -674);
FORCEPROP 1 LAST Q_DEPT 
J 1
(-713 -651);
DISPLAY 1.957447 (-713 -651);
PAINT GREEN (-713 -651);
FORCEPROP 2 LAST CDS_XR_PAGE_TITLE CR-212 : @S9S_MB_2U_LIB.S9S_MB_2U(SCH_1):PAGE212
J 0
(-4840 4550);
DISPLAY 0.638298 (-4840 4550);
PAINT PINK (-4840 4550);
DISPLAY INVISIBLE (-4840 4550);
FORCEPROP 2 LAST CDS_LIB pure_quanta
J 0
(3050 -700);
DISPLAY INVISIBLE (3050 -700);
FORCEPROP 1 LAST CDS_LMAN_SYM_OUTLINE -9475,6775,100,-125
J 0
(3050 -700);
DISPLAY 0.468085 (3050 -700);
PAINT GREEN (3050 -700);
DISPLAY INVISIBLE (3050 -700);
FORCEPROP 1 LAST COMMENT_BODY TRUE
J 0
(3062 -713);
DISPLAY 0.978723 (3062 -713);
PAINT GREEN (3062 -713);
DISPLAY INVISIBLE (3062 -713);
FORCEPROP 2 LAST PAGE_BORDER TRUE
J 0
(-4840 4550);
DISPLAY 0.638298 (-4840 4550);
PAINT PINK (-4840 4550);
DISPLAY INVISIBLE (-4840 4550);
WIRE 16 -1 (-5075 3825)(-5075 3950);
WIRE 16 -1 (-2850 4100)(-2850 4250);
WIRE 16 -1 (-2075 4100)(-2850 4100);
WIRE 16 -1 (-3500 5275)(-3500 5200);
WIRE 16 -1 (-2375 2300)(-2375 2175);
WIRE 16 -1 (1575 2400)(1575 2525);
WIRE 16 -1 (-2500 4150)(-2500 4325);
WIRE 16 -1 (-1950 4150)(-2500 4150);
WIRE 16 -1 (-3425 1700)(-3425 1825);
WIRE 16 -1 (1575 1600)(1575 1725);
WIRE 16 -1 (-725 5250)(-725 5200);
WIRE 16 -1 (-2400 5300)(-2400 5200);
WIRE 16 -1 (250 1575)(250 1700);
WIRE 16 -1 (-4350 3600)(-4350 3550);
WIRE 16 -1 (-4225 3700)(-4225 3650);
WIRE 16 -1 (-4175 3700)(-4225 3700);
WIRE 16 -1 (-3475 3600)(-3475 3525);
WIRE 16 -1 (-3575 3700)(-3575 3650);
WIRE 16 -1 (-3625 3700)(-3575 3700);
WIRE 16 -1 (-1600 4775)(-1600 4700);
WIRE 16 -1 (-1600 4775)(-1850 4775);
WIRE 16 -1 (-1600 4900)(-1600 4775);
WIRE 16 -1 (-725 4775)(-725 4700);
WIRE 16 -1 (-1050 4775)(-725 4775);
WIRE 16 -1 (-725 4875)(-725 4775);
WIRE 16 -1 (250 900)(250 775);
WIRE 16 -1 (1575 925)(1575 800);
WIRE 16 -1 (-700 2550)(-700 2850);
WIRE 16 -1 (-2375 1725)(-2375 1825);
WIRE 16 -1 (-2550 1150)(-2550 1025);
WIRE 16 -1 (-2425 1150)(-2550 1150);
WIRE 16 -1 (-3400 875)(-3400 575);
WIRE 16 -1 (-3025 3050)(-1950 3050);
FORCEPROP 0 LAST CDS_PHYS_NET_NAME FM_PCH_PRSNT_N
J 0
(-3000 3092);
PAINT MONO (-3000 3092);
DISPLAY INVISIBLE (-3000 3092);
FORCEPROP 0 LAST SIG_NAME P3V3_PWRGD_CLKGEN
J 0
(-2960 3060);
DISPLAY 0.680851 (-2960 3060);
PAINT WHITE (-2960 3060);
WIRE 16 -1 (-2575 1350)(-2425 1350);
WIRE 16 -1 (-2375 2025)(-2375 2175);
WIRE 16 -1 (-2575 2175)(-2575 1350);
WIRE 16 -1 (-2575 2175)(-2375 2175);
WIRE 16 -1 (-3225 3750)(-1950 3750);
FORCEPROP 2 LAST SIG_NAME CLK_GEN2_XTAL_IN
J 0
(-2960 3760);
DISPLAY 0.638298 (-2960 3760);
PAINT WHITE (-2960 3760);
WIRE 16 -1 (-3225 4375)(-3225 3750);
WIRE 16 -1 (-3375 4375)(-3225 4375);
WIRE 16 -1 (-3625 3900)(-3475 3900);
WIRE 16 -1 (-3475 3800)(-3475 3900);
WIRE 16 -1 (-3300 3900)(-3475 3900);
WIRE 16 -1 (-3300 3900)(-3300 3700);
WIRE 16 -1 (-3300 3700)(-1950 3700);
FORCEPROP 2 LAST SIG_NAME CLK_GEN2_XTAL_OUT
J 0
(-2960 3710);
DISPLAY 0.638298 (-2960 3710);
PAINT WHITE (-2960 3710);
WIRE 16 -1 (-1950 4100)(-2075 4100);
WIRE 16 -1 (-1950 4050)(-2075 4050);
WIRE 16 -1 (-2075 4100)(-2075 4050);
WIRE 16 -1 (-2075 4050)(-2075 4000);
WIRE 16 -1 (-1950 4000)(-2075 4000);
WIRE 16 -1 (-2075 4000)(-2075 3950);
WIRE 16 -1 (-2075 3950)(-1950 3950);
WIRE 16 -1 (-850 4150)(-200 4150);
FORCEPROP 0 LAST CDS_PHYS_NET_NAME FM_PCH_PRSNT_N
J 0
(-825 4192);
PAINT MONO (-825 4192);
DISPLAY INVISIBLE (-825 4192);
FORCEPROP 0 LAST SIG_NAME CLK_GEN2_SMB_SADR
J 0
(-750 4160);
DISPLAY 0.680851 (-750 4160);
PAINT WHITE (-750 4160);
WIRE 16 -1 (-850 2850)(-700 2850);
WIRE 16 -1 (-850 3000)(-700 3000);
WIRE 16 -1 (-700 2850)(-700 3000);
WIRE 16 -1 (-850 3050)(-700 3050);
WIRE 16 -1 (-700 3050)(-700 3000);
WIRE 16 -1 (-700 3100)(-700 3050);
WIRE 16 -1 (-850 3100)(-700 3100);
WIRE 16 -1 (-850 3150)(-700 3150);
WIRE 16 -1 (-700 3150)(-700 3100);
WIRE 16 -1 (-850 3200)(-700 3200);
WIRE 16 -1 (-700 3200)(-700 3150);
WIRE 16 -1 (-700 3250)(-700 3200);
WIRE 16 -1 (-850 3250)(-700 3250);
WIRE 16 -1 (-1950 3500)(-3000 3500);
FORCEPROP 2 LAST SIG_NAME SMB_HOST_CLK_GEN2_3V3AUX_SCL
J 0
(-2960 3510);
DISPLAY 0.702128 (-2960 3510);
PAINT WHITE (-2960 3510);
WIRE 16 -1 (-1950 3450)(-3000 3450);
FORCEPROP 2 LAST SIG_NAME SMB_HOST_CLK_GEN2_3V3AUX_SDA
J 0
(-2960 3460);
DISPLAY 0.702128 (-2960 3460);
PAINT WHITE (-2960 3460);
WIRE 16 -1 (-3200 3350)(-1950 3350);
FORCEPROP 2 LAST SIG_NAME CLK_GEN2_BMC_RC_OE_R3_N
J 0
(-2960 3360);
DISPLAY 0.680851 (-2960 3360);
PAINT WHITE (-2960 3360);
WIRE 16 -1 (75 3750)(-850 3750);
FORCEPROP 2 LAST SIG_NAME CLK_100M_BMC_RC_DP_R
J 0
(-760 3760);
DISPLAY 0.680851 (-760 3760);
PAINT WHITE (-760 3760);
WIRE 16 -1 (75 3700)(-850 3700);
FORCEPROP 2 LAST SIG_NAME CLK_100M_BMC_RC_DN_R
J 0
(-760 3710);
DISPLAY 0.680851 (-760 3710);
PAINT WHITE (-760 3710);
WIRE 16 -1 (75 3600)(-850 3600);
FORCEPROP 2 LAST SIG_NAME CLK_100M_GPU_FPGA_DP_R
J 0
(-760 3610);
DISPLAY 0.680851 (-760 3610);
PAINT WHITE (-760 3610);
WIRE 16 -1 (75 3550)(-850 3550);
FORCEPROP 2 LAST SIG_NAME CLK_100M_GPU_FPGA_DN_R
J 0
(-760 3560);
DISPLAY 0.680851 (-760 3560);
PAINT WHITE (-760 3560);
WIRE 16 -1 (-3200 3300)(-1950 3300);
FORCEPROP 2 LAST SIG_NAME CLK_GEN2_GPU_OE_N
J 0
(-2960 3310);
DISPLAY 0.680851 (-2960 3310);
PAINT WHITE (-2960 3310);
WIRE 16 -1 (-3025 2950)(-1950 2950);
FORCEPROP 0 LAST CDS_PHYS_NET_NAME FM_PCH_PRSNT_N
J 0
(-3000 2992);
PAINT MONO (-3000 2992);
DISPLAY INVISIBLE (-3000 2992);
FORCEPROP 0 LAST SIG_NAME FG_SS_EN
J 0
(-2960 2960);
DISPLAY 0.680851 (-2960 2960);
PAINT WHITE (-2960 2960);
WIRE 16 2175 (-4725 3875)(-4250 3875);
WIRE 16 2175 (-4250 3875)(-4250 3425);
WIRE 16 2175 (-4725 3875)(-4725 3425);
WIRE 16 2175 (-4725 3425)(-4250 3425);
WIRE 16 -1 (-4350 3900)(-4350 3800);
WIRE 16 -1 (-4175 3900)(-4350 3900);
WIRE 16 -1 (-4350 3900)(-4350 4375);
WIRE 16 -1 (-4350 4375)(-3575 4375);
FORCEPROP 2 LAST SIG_NAME CLK_GEN2_XTAL_IN_R
J 0
(-4285 4385);
DISPLAY 0.553191 (-4285 4385);
PAINT WHITE (-4285 4385);
WIRE 16 2175 (-3525 3450)(-3150 3450);
WIRE 16 2175 (-3150 3975)(-3150 3450);
WIRE 16 2175 (-3525 3975)(-3525 3450);
WIRE 16 2175 (-3525 3975)(-3150 3975);
WIRE 16 -1 (-5075 3625)(-5075 3350);
WIRE 16 -1 (-5075 3350)(-3400 3350);
FORCEPROP 2 LAST SIG_NAME CLK_GEN2_BMC_RC_OE_N
J 0
(-4485 3360);
DISPLAY 0.680851 (-4485 3360);
PAINT WHITE (-4485 3360);
WIRE 16 -1 (-5150 3350)(-5075 3350);
WIRE 16 -1 (-5150 3300)(-3400 3300);
FORCEPROP 2 LAST SIG_NAME CLK_GEN2_GPU_FPGA_OE_OR_N
J 0
(-4485 3310);
DISPLAY 0.680851 (-4485 3310);
PAINT WHITE (-4485 3310);
WIRE 16 -1 (-3625 1300)(-2525 1300);
FORCEPROP 2 LAST SIG_NAME GPU_FPGA_READY_R_N
J 0
(-3385 1310);
DISPLAY 0.680851 (-3385 1310);
PAINT WHITE (-3385 1310);
WIRE 16 -1 (-3425 1200)(-3625 1200);
WIRE 16 -1 (-3425 1500)(-3425 1200);
WIRE 16 -1 (-3400 1200)(-3425 1200);
WIRE 16 -1 (-2525 1200)(-3400 1200);
FORCEPROP 2 LAST SIG_NAME CLK_GEN2_GPU_FPGA_OE_R2_N
J 0
(-3385 1210);
DISPLAY 0.680851 (-3385 1210);
PAINT WHITE (-3385 1210);
WIRE 16 -1 (-3400 1075)(-3400 1200);
WIRE 16 2175 (-2625 900)(-1850 900);
WIRE 16 2175 (-1850 1675)(-1850 900);
WIRE 16 2175 (-2625 1675)(-2625 900);
WIRE 16 2175 (-2625 1675)(-1850 1675);
WIRE 16 -1 (-1050 4875)(-1050 4775);
WIRE 16 -1 (-1600 5100)(-1600 5200);
WIRE 16 -1 (-1375 5200)(-1600 5200);
WIRE 16 -1 (-1850 5100)(-1850 5200);
WIRE 16 -1 (-1600 5200)(-1850 5200);
WIRE 16 -1 (-2075 5100)(-2075 5200);
WIRE 16 -1 (-2075 5200)(-1850 5200);
WIRE 16 -1 (-2400 5100)(-2400 5200);
WIRE 16 -1 (-2400 5200)(-2075 5200);
WIRE 16 -1 (-2800 5200)(-2800 5100);
WIRE 16 -1 (-3050 5200)(-2800 5200);
WIRE 16 -1 (-2800 5200)(-2400 5200);
WIRE 16 -1 (-1050 5075)(-1050 5200);
WIRE 16 -1 (-1050 5200)(-1175 5200);
WIRE 16 -1 (-725 5200)(-1050 5200);
WIRE 16 -1 (-725 5075)(-725 5200);
WIRE 16 -1 (-3500 5200)(-3250 5200);
WIRE 16 -1 (-2800 4775)(-2800 4900);
WIRE 16 -1 (-2400 4775)(-2800 4775);
WIRE 16 -1 (-2400 4900)(-2400 4775);
WIRE 16 -1 (-2400 4775)(-2075 4775);
WIRE 16 -1 (-2075 4900)(-2075 4775);
WIRE 16 -1 (-2075 4775)(-1850 4775);
WIRE 16 -1 (-1850 4900)(-1850 4775);
WIRE 16 -1 (1575 1250)(1575 1125);
WIRE 16 -1 (1575 1400)(1575 1250);
WIRE 16 -1 (1575 1250)(2225 1250);
FORCEPROP 0 LAST CDS_PHYS_NET_NAME FM_PCH_PRSNT_N
J 0
(1600 1292);
PAINT MONO (1600 1292);
DISPLAY INVISIBLE (1600 1292);
FORCEPROP 0 LAST SIG_NAME CLK_GEN2_SMB_SADR
J 0
(1675 1260);
DISPLAY 0.680851 (1675 1260);
PAINT WHITE (1675 1260);
WIRE 16 -1 (-3825 1200)(-4725 1200);
FORCEPROP 2 LAST SIG_NAME CLK_GEN2_GPU_FPGA_OE_N
J 0
(-4660 1210);
DISPLAY 0.680851 (-4660 1210);
PAINT WHITE (-4660 1210);
WIRE 16 -1 (-3825 1300)(-4725 1300);
FORCEPROP 2 LAST SIG_NAME GPU_FPGA_READY_N
J 0
(-4660 1310);
DISPLAY 0.680851 (-4660 1310);
PAINT WHITE (-4660 1310);
WIRE 16 -1 (1200 3550)(275 3550);
FORCEPROP 2 LAST SIG_NAME CLK_100M_GPU_FPGA_DN
J 0
(540 3560);
DISPLAY 0.680851 (540 3560);
PAINT WHITE (540 3560);
WIRE 16 -1 (1200 3600)(275 3600);
FORCEPROP 2 LAST SIG_NAME CLK_100M_GPU_FPGA_DP
J 0
(540 3610);
DISPLAY 0.680851 (540 3610);
PAINT WHITE (540 3610);
WIRE 16 -1 (-1925 1250)(-925 1250);
FORCEPROP 2 LAST SIG_NAME CLK_GEN2_GPU_FPGA_OE_OR_N
J 0
(-1835 1260);
DISPLAY 0.680851 (-1835 1260);
PAINT WHITE (-1835 1260);
WIRE 16 -1 (250 1225)(250 1100);
WIRE 16 -1 (250 1375)(250 1225);
WIRE 16 -1 (250 1225)(900 1225);
FORCEPROP 0 LAST CDS_PHYS_NET_NAME FM_PCH_PRSNT_N
J 0
(275 1267);
PAINT MONO (275 1267);
DISPLAY INVISIBLE (275 1267);
FORCEPROP 0 LAST SIG_NAME FG_SS_EN
J 0
(350 1235);
DISPLAY 0.680851 (350 1235);
PAINT WHITE (350 1235);
WIRE 16 -1 (1200 3750)(275 3750);
FORCEPROP 2 LAST SIG_NAME CLK_100M_BMC_RC_DP
J 0
(540 3760);
DISPLAY 0.680851 (540 3760);
PAINT WHITE (540 3760);
WIRE 16 -1 (1200 3700)(275 3700);
FORCEPROP 2 LAST SIG_NAME CLK_100M_BMC_RC_DN
J 0
(540 3710);
DISPLAY 0.680851 (540 3710);
PAINT WHITE (540 3710);
WIRE 16 -1 (1575 2050)(2225 2050);
FORCEPROP 0 LAST CDS_PHYS_NET_NAME FM_PCH_PRSNT_N
J 0
(1600 2092);
PAINT MONO (1600 2092);
DISPLAY INVISIBLE (1600 2092);
FORCEPROP 0 LAST SIG_NAME P3V3_PWRGD_CLKGEN
J 0
(1675 2060);
DISPLAY 0.680851 (1675 2060);
PAINT WHITE (1675 2060);
WIRE 16 -1 (1575 2200)(1575 2050);
DOT 1 (-3475 3900);
DOT 1 (-4350 3900);
DOT 1 (-2075 4100);
DOT 1 (250 1225);
DOT 1 (-1600 4775);
DOT 1 (-700 3050);
DOT 1 (-700 3100);
DOT 1 (-700 3200);
DOT 1 (-700 2850);
DOT 1 (-700 3000);
DOT 1 (-2075 4000);
DOT 1 (-2075 4050);
DOT 1 (-725 5200);
DOT 1 (-1050 5200);
DOT 1 (-725 4775);
DOT 1 (-1600 5200);
DOT 1 (-1850 5200);
DOT 1 (-2075 5200);
DOT 1 (-1850 4775);
DOT 1 (-2075 4775);
DOT 1 (-2400 5200);
DOT 1 (-2800 5200);
DOT 1 (-2400 4775);
DOT 1 (-700 3150);
DOT 1 (1575 1250);
DOT 1 (-2375 2175);
DOT 1 (-3400 1200);
DOT 1 (-3425 1200);
DOT 1 (-5075 3350);
FORCENOTE
20220620 CHANGE TO 8.2PF
(-5275 4150) 0;
DISPLAY LEFT (-5275 4150);
DISPLAY 0.808511 (-5275 4150);
PAINT PINK (-5275 4150);
FORCENOTE
20210602 MODIFY FOR GT
(-6050 5675) 0;
DISPLAY LEFT (-6050 5675);
DISPLAY 2.510638 (-6050 5675);
PAINT PINK (-6050 5675);
FORCENOTE
20211129 U248 CHANGE TO OR GATE
(-2900 775) 0;
DISPLAY LEFT (-2900 775);
DISPLAY 1.063830 (-2900 775);
PAINT WHITE (-2900 775);
FORCENOTE
TO BMC
(1575 3700) 0;
DISPLAY LEFT (1575 3700);
DISPLAY 1.340425 (1575 3700);
PAINT WHITE (1575 3700);
FORCENOTE
13 MA
(-2400 4175) 0;
DISPLAY LEFT (-2400 4175);
DISPLAY 0.851064 (-2400 4175);
PAINT WHITE (-2400 4175);
FORCENOTE
TO GPU FPGA
(1575 3550) 0;
DISPLAY LEFT (1575 3550);
DISPLAY 1.340425 (1575 3550);
PAINT WHITE (1575 3550);
FORCENOTE
20 MA
(-2750 4125) 0;
DISPLAY LEFT (-2750 4125);
DISPLAY 0.851064 (-2750 4125);
PAINT WHITE (-2750 4125);
FORCENOTE
ADDRESS: 0XD4
(-1850 2575) 0;
DISPLAY LEFT (-1850 2575);
DISPLAY 1.595745 (-1850 2575);
PAINT SKYBLUE (-1850 2575);
QUIT
